G04 ================== begin FILE IDENTIFICATION RECORD ==================*
G04 Layout Name:  9054_F0T_PDB_BD_GPU_F_V04_1213_1550.brd*
G04 Film Name:    smt*
G04 File Format:  Gerber RS274X*
G04 File Origin:  Cadence Allegro 17.2-S081*
G04 Origin Date:  Wed Dec 28 10:19:02 2022*
G04 *
G04 Layer:  DRAWING FORMAT/TITLE_BLOCK_A*
G04 Layer:  DRAWING FORMAT/TITLE_BLOCK*
G04 Layer:  VIA CLASS/SOLDERMASK_TOP*
G04 Layer:  PIN/SOLDERMASK_TOP*
G04 Layer:  PACKAGE GEOMETRY/SOLDERMASK_TOP*
G04 Layer:  MANUFACTURING/PHOTOPLOT_OUTLINE*
G04 Layer:  DRAWING FORMAT/TITLE_DATA_SMT*
G04 Layer:  BOARD GEOMETRY/SOLDERMASK_TOP*
G04 *
G04 Offset:    (0.00 0.00)*
G04 Mirror:    No*
G04 Mode:      Positive*
G04 Rotation:  0*
G04 FullContactRelief:  No*
G04 UndefLineWidth:     6.00*
G04 ================== end FILE IDENTIFICATION RECORD ====================*
%FSLAX25Y25*MOIN*%
%IR0*IPPOS*OFA0.00000B0.00000*MIA0B0*SFA1.00000B1.00000*%
%AMMACRO80*
4,1,5,.01972,-.00791,
-.01264,-.00791,
-.01972,-.00083,
-.01972,.00791,
.01972,.00791,
.01972,-.00791,
0.0*
%
%ADD80MACRO80*%
%AMMACRO82*
4,1,32,-.01575,.06201,
-.01575,.0502,
.00197,.0502,
.00197,.04035,
-.01575,.04035,
-.01575,.03248,
.00197,.03248,
.00197,.02461,
-.01575,.02461,
-.01575,.01673,
.00197,.01673,
.00197,.00886,
-.01575,.00886,
-.01575,.00098,
.00197,.00098,
.00197,-.00689,
-.01575,-.00689,
-.01575,-.01476,
.00197,-.01476,
.00197,-.02264,
-.01575,-.02264,
-.01575,-.03051,
.00197,-.03051,
.00197,-.03839,
-.01575,-.03839,
-.01575,-.04626,
.00197,-.04626,
.00197,-.05413,
-.01575,-.05413,
-.01575,-.06201,
.01575,-.06201,
.01575,.06201,
-.01575,.06201,
0.0*
%
%ADD82MACRO82*%
%AMMACRO60*
4,1,8,-.16834,.21066,
-.07576,.21066,
-.07576,.14964,
.16834,.14964,
.16834,-.14964,
-.07576,-.14964,
-.07576,-.21066,
-.16834,-.21066,
-.16834,.21066,
0.0*
%
%ADD60MACRO60*%
%ADD61R,.103X.071*%
%ADD84R,.046X.103*%
%ADD76R,.067X.123*%
%ADD75R,.142X.067*%
%ADD37R,.126X.056*%
%ADD58C,.07*%
%ADD23R,.067X.142*%
%ADD19R,.056X.126*%
%ADD12C,.034*%
%ADD86O,.127X.078*%
%ADD87C,.065*%
%ADD21C,.074*%
%ADD51C,.085*%
%ADD57R,.07X.07*%
%ADD53C,.06415*%
%ADD22R,.074X.074*%
%ADD17C,.04952*%
%ADD56R,.06415X.06415*%
%AMMACRO28*
4,1,28,-.00589,-.01192,
-.006913,-.011842,
-.007907,-.011587,
-.008842,-.011163,
-.009688,-.010584,
-.010422,-.009866,
-.011019,-.009032,
-.011463,-.008107,
-.011739,-.007119,
-.01184,-.006097,
-.01184,-.00603,
-.01184,.00148,
-.00948,.00148,
-.00948,.01191,
.00948,.01191,
.00948,.00148,
.01184,.00148,
.01184,-.00603,
.011751,-.007052,
.011486,-.008044,
.011053,-.008974,
.010465,-.009815,
.00974,-.010541,
.0089,-.01113,
.00797,-.011564,
.006979,-.01183,
.005957,-.01192,
.00589,-.01192,
-.00589,-.01192,
0.0*
%
%ADD28MACRO28*%
%AMMACRO49*
4,1,28,-.01192,.00589,
-.011842,.006913,
-.011587,.007907,
-.011163,.008842,
-.010584,.009688,
-.009866,.010422,
-.009032,.011019,
-.008107,.011463,
-.007119,.011739,
-.006097,.01184,
-.00603,.01184,
.00148,.01184,
.00148,.00948,
.01191,.00948,
.01191,-.00948,
.00148,-.00948,
.00148,-.01184,
-.00603,-.01184,
-.007052,-.011751,
-.008044,-.011486,
-.008974,-.011053,
-.009815,-.010465,
-.010541,-.00974,
-.01113,-.0089,
-.011564,-.00797,
-.01183,-.006979,
-.01192,-.005957,
-.01192,-.00589,
-.01192,.00589,
0.0*
%
%ADD49MACRO49*%
%ADD18R,.04952X.04952*%
%AMMACRO32*
4,1,28,.0059,.01191,
.006923,.01183,
.007916,.011573,
.00885,.011148,
.009696,.010567,
.010428,.009849,
.011024,.009013,
.011466,.008088,
.011741,.007099,
.01184,.006078,
.01184,.00602,
.01184,-.00149,
.00948,-.00149,
.00948,-.01192,
-.00948,-.01192,
-.00948,-.00149,
-.01184,-.00149,
-.01184,.00602,
-.011751,.007042,
-.011486,.008033,
-.011053,.008964,
-.010465,.009805,
-.00974,.010531,
-.0089,.01112,
-.007971,.011554,
-.00698,.01182,
-.005958,.01191,
-.0059,.01191,
.0059,.01191,
0.0*
%
%ADD32MACRO32*%
%AMMACRO48*
4,1,28,.01191,-.0059,
.01183,-.006923,
.011573,-.007916,
.011148,-.00885,
.010567,-.009696,
.009849,-.010428,
.009013,-.011024,
.008088,-.011466,
.007099,-.011741,
.006078,-.01184,
.00602,-.01184,
-.00149,-.01184,
-.00149,-.00948,
-.01192,-.00948,
-.01192,.00948,
-.00149,.00948,
-.00149,.01184,
.00602,.01184,
.007042,.011751,
.008033,.011486,
.008964,.011053,
.009805,.010465,
.010531,.00974,
.01112,.0089,
.011554,.007971,
.01182,.00698,
.01191,.005958,
.01191,.0059,
.01191,-.0059,
0.0*
%
%ADD48MACRO48*%
%ADD31R,.134X.103*%
%ADD77R,.142X.132*%
%ADD62R,.024X.022*%
%ADD83R,.036X.011*%
%ADD40R,.022X.024*%
%AMMACRO20*
4,1,8,.21066,.16834,
.21066,.07576,
.14964,.07576,
.14964,-.16834,
-.14964,-.16834,
-.14964,.07576,
-.21066,.07576,
-.21066,.16834,
.21066,.16834,
0.0*
%
%ADD20MACRO20*%
%ADD43R,.014X.024*%
%AMMACRO39*
4,1,8,.16834,-.21066,
.07576,-.21066,
.07576,-.14964,
-.16834,-.14964,
-.16834,.14964,
.07576,.14964,
.07576,.21066,
.16834,.21066,
.16834,-.21066,
0.0*
%
%ADD39MACRO39*%
%ADD52R,.04X.036*%
%ADD41R,.13X.274*%
%ADD33C,.103*%
%ADD64R,.036X.014*%
%ADD59R,.036X.04*%
%ADD47R,.021X.028*%
%ADD42R,.036X.032*%
%ADD74R,.032X.028*%
%ADD73R,.056X.022*%
%ADD72R,.06X.018*%
%ADD65R,.014X.036*%
%ADD63R,.014X.054*%
%ADD38R,.032X.036*%
%ADD35C,.105*%
%ADD88C,.106*%
%ADD78R,.036X.016*%
%ADD34C,.115*%
%ADD16R,.028X.032*%
%ADD71R,.072X.026*%
%ADD54C,.26*%
%ADD50R,.036X.026*%
%ADD24R,.054X.044*%
%ADD10C,.404*%
%ADD81R,.044X.054*%
%ADD70R,.026X.072*%
%ADD66R,.063X.018*%
%ADD79R,.016X.083*%
%ADD27C,.145*%
%ADD25R,.036X.028*%
%ADD14C,.118*%
%ADD26R,.067X.044*%
%ADD85C,.418*%
%ADD55C,.319*%
%ADD15R,.044X.067*%
%ADD46R,.058X.048*%
%ADD13C,.178*%
%ADD36R,.048X.058*%
%ADD11O,.359X.556*%
%ADD69R,.093X.089*%
%AMMACRO68*
4,1,5,.00692,-.01362,
.00181,-.01873,
-.00692,-.01873,
-.00692,.01873,
.00692,.01873,
.00692,-.01362,
0.0*
%
%ADD68MACRO68*%
%AMMACRO45*
4,1,28,.01192,-.00589,
.011842,-.006913,
.011587,-.007907,
.011163,-.008842,
.010584,-.009688,
.009866,-.010422,
.009032,-.011019,
.008107,-.011463,
.007119,-.011739,
.006097,-.01184,
.00603,-.01184,
-.00148,-.01184,
-.00148,-.00948,
-.01191,-.00948,
-.01191,.00948,
-.00148,.00948,
-.00148,.01184,
.00603,.01184,
.007052,.011751,
.008044,.011486,
.008974,.011053,
.009815,.010465,
.010541,.00974,
.01113,.0089,
.011564,.00797,
.01183,.006979,
.01192,.005957,
.01192,.00589,
.01192,-.00589,
0.0*
%
%ADD45MACRO45*%
%AMMACRO30*
4,1,28,.00589,.01192,
.006913,.011842,
.007907,.011587,
.008842,.011163,
.009688,.010584,
.010422,.009866,
.011019,.009032,
.011463,.008107,
.011739,.007119,
.01184,.006097,
.01184,.00603,
.01184,-.00148,
.00948,-.00148,
.00948,-.01191,
-.00948,-.01191,
-.00948,-.00148,
-.01184,-.00148,
-.01184,.00603,
-.011751,.007052,
-.011486,.008044,
-.011053,.008974,
-.010465,.009815,
-.00974,.010541,
-.0089,.01113,
-.00797,.011564,
-.006979,.01183,
-.005957,.01192,
-.00589,.01192,
.00589,.01192,
0.0*
%
%ADD30MACRO30*%
%AMMACRO67*
4,1,8,-.02021,-.02661,
-.02021,.0266,
.02021,.0266,
.02021,.01276,
-.00637,.01276,
-.00637,-.01277,
.02021,-.01277,
.02021,-.02661,
-.02021,-.02661,
0.0*
%
%ADD67MACRO67*%
%AMMACRO44*
4,1,28,-.01191,.0059,
-.01183,.006923,
-.011573,.007916,
-.011148,.00885,
-.010567,.009696,
-.009849,.010428,
-.009013,.011024,
-.008088,.011466,
-.007099,.011741,
-.006078,.01184,
-.00602,.01184,
.00149,.01184,
.00149,.00948,
.01192,.00948,
.01192,-.00948,
.00149,-.00948,
.00149,-.01184,
-.00602,-.01184,
-.007042,-.011751,
-.008033,-.011486,
-.008964,-.011053,
-.009805,-.010465,
-.010531,-.00974,
-.01112,-.0089,
-.011554,-.007971,
-.01182,-.00698,
-.01191,-.005958,
-.01191,-.0059,
-.01191,.0059,
0.0*
%
%ADD44MACRO44*%
%AMMACRO29*
4,1,28,-.0059,-.01191,
-.006923,-.01183,
-.007916,-.011573,
-.00885,-.011148,
-.009696,-.010567,
-.010428,-.009849,
-.011024,-.009013,
-.011466,-.008088,
-.011741,-.007099,
-.01184,-.006078,
-.01184,-.00602,
-.01184,.00149,
-.00948,.00149,
-.00948,.01192,
.00948,.01192,
.00948,.00149,
.01184,.00149,
.01184,-.00602,
.011751,-.007042,
.011486,-.008033,
.011053,-.008964,
.010465,-.009805,
.00974,-.010531,
.0089,-.01112,
.007971,-.011554,
.00698,-.01182,
.005958,-.01191,
.0059,-.01191,
-.0059,-.01191,
0.0*
%
%ADD29MACRO29*%
%ADD89C,.02*%
%ADD90C,.006*%
%ADD91C,.1942*%
G75*
%LPD*%
G75*
G36*
G01X78955Y236614D02*
G02I-19900J0D01*
G37*
G36*
G01Y411594D02*
G02I-19900J0D01*
G37*
G36*
G01X105049Y604098D02*
G03I-5900J0D01*
G37*
G36*
G01X1030787Y231919D02*
G03I-5900J0D01*
G37*
G36*
G01X1647431Y219808D02*
G03I-5900J0D01*
G37*
G36*
G01X1693128Y236614D02*
G02I-19900J0D01*
G37*
G36*
G01Y411614D02*
G02I-19900J0D01*
G37*
G36*
G01X1722830Y503124D02*
G03I-5900J0D01*
G37*
%LPC*%
G75*
G54D91*
X59055Y236614D03*
Y411594D03*
X1673228Y236614D03*
Y411614D03*
%LPD*%
G75*
G54D10*
X32284Y541339D03*
X59055Y498032D03*
X1673228D03*
X1700000Y541339D03*
G54D11*
X47244Y27558D03*
Y340550D03*
X279528Y62990D03*
X314961Y570865D03*
X393702Y354330D03*
X748032Y74803D03*
Y354330D03*
X984252Y74803D03*
Y354330D03*
X1338584D03*
X1417324Y570865D03*
X1452756Y62991D03*
X1685040Y27558D03*
Y340550D03*
X1799212Y106299D03*
Y488188D03*
G54D20*
X166785Y150901D03*
X1565500Y144901D03*
G54D30*
X208000Y105983D03*
X317000Y71983D03*
X321500D03*
X392000Y46783D03*
X663500Y317483D03*
X732000Y310483D03*
X1490228Y71984D03*
X1494728D03*
X1622100Y151983D03*
X1618500Y185483D03*
X1653270Y130423D03*
X1690100Y124883D03*
X1685100D03*
X1707500Y198483D03*
X1711600Y147983D03*
X1717100D03*
X1712000Y163483D03*
X1716500D03*
X1768500Y147983D03*
Y163483D03*
X1773000Y147983D03*
Y163483D03*
X1778000Y195483D03*
X1786600Y246483D03*
X1775816Y339557D03*
X1771816D03*
X1779816D03*
G54D21*
X166785Y200472D03*
Y280472D03*
Y360472D03*
Y440472D03*
Y520472D03*
X243785Y200472D03*
Y280472D03*
Y360472D03*
Y440472D03*
Y520472D03*
X1488500Y200472D03*
Y280472D03*
Y360472D03*
Y440472D03*
Y520472D03*
X1565500Y200472D03*
Y280472D03*
Y360472D03*
Y440472D03*
Y520472D03*
G54D12*
X45275Y236614D03*
Y411594D03*
X72835Y236614D03*
X68898Y226771D03*
X59055Y222834D03*
X49212Y226771D03*
X68898Y246457D03*
X49212D03*
X59055Y250394D03*
X68898Y421437D03*
X72835Y411594D03*
X68898Y401751D03*
X59055Y397814D03*
X49212Y401751D03*
Y421437D03*
X59055Y425374D03*
X124600Y120500D03*
X120840Y145500D03*
X121100Y163500D03*
X206900Y110700D03*
X202924Y102925D03*
X254000Y141000D03*
X263000D03*
X325100Y64000D03*
X439400Y81900D03*
X439500Y126300D03*
X436500Y175600D03*
X437200Y219100D03*
X438800Y259500D03*
X439100Y303900D03*
X484100Y325500D03*
X485300Y332100D03*
X536000Y57000D03*
X548000Y68000D03*
X547000Y87000D03*
X543000Y172000D03*
X533000Y156000D03*
X547000Y195000D03*
X546000Y215000D03*
X537000Y227000D03*
X534000Y275000D03*
X564305Y160784D03*
X590298Y282890D03*
X571325Y292757D03*
X590298Y276984D03*
X612684Y297000D03*
X606084Y293100D03*
X616684Y307975D03*
X622184Y308000D03*
X608259Y305000D03*
X639010Y236377D03*
X645900Y242200D03*
X650500Y246600D03*
X637684Y280575D03*
X625684Y273499D03*
X630308Y284500D03*
X649500Y308500D03*
X674800Y269600D03*
X671400Y261000D03*
X666759Y274800D03*
X679184Y273190D03*
X671000Y331925D03*
X685884Y297000D03*
X736554Y131056D03*
X742554Y128056D03*
X726100Y185000D03*
X717384Y273400D03*
X718000Y300000D03*
X714045Y326886D03*
X809400Y362200D03*
X923100D03*
X980500Y185000D03*
X996954Y128056D03*
X1027675Y215000D03*
X1044900Y278600D03*
X1074430Y256461D03*
X1091800Y279100D03*
X1083100Y278810D03*
X1090200Y288600D03*
X1131976Y267500D03*
X1133100Y277700D03*
X1123100Y322500D03*
X1112136Y305400D03*
X1123400Y356300D03*
X1145600Y257500D03*
X1156200Y258900D03*
X1145600Y244025D03*
X1140100Y244000D03*
X1163266Y255311D03*
X1171600Y238000D03*
X1171986Y269110D03*
X1187700Y288000D03*
X1196500Y293284D03*
X1171986Y275016D03*
X1179500Y355000D03*
X1214000Y83000D03*
X1223000Y96000D03*
X1200575Y160284D03*
X1225000Y165000D03*
X1214000Y177000D03*
X1223000Y197000D03*
X1212000Y215000D03*
X1227000Y223000D03*
X1226000Y251000D03*
X1201500Y293284D03*
X1199100Y273500D03*
X1228000Y274000D03*
X1278200Y329500D03*
X1263100Y343200D03*
X1323900Y62100D03*
X1323500Y106500D03*
X1324000Y156000D03*
Y199000D03*
X1323700Y239700D03*
X1323000Y284100D03*
X1406230Y21076D03*
X1400230Y15076D03*
X1498180Y63500D03*
X1529400Y102075D03*
X1524600Y119500D03*
X1607100Y115000D03*
X1618177Y120474D03*
X1611100Y138500D03*
X1612100Y154000D03*
X1620500Y170500D03*
X1620000Y177500D03*
X1630527Y90564D03*
X1646500Y94000D03*
X1627366Y143500D03*
X1622388Y127365D03*
X1634200Y180500D03*
X1636600Y173500D03*
X1621500Y159000D03*
Y165000D03*
X1636500Y168000D03*
Y162500D03*
X1648925Y194000D03*
X1635163Y200500D03*
X1674600Y176000D03*
X1674100Y168280D03*
X1673600Y158500D03*
X1657500Y191500D03*
X1667600Y198500D03*
X1673228Y222834D03*
X1663385Y226771D03*
X1659448Y236614D03*
X1663385Y246457D03*
X1673228Y250394D03*
Y397834D03*
X1663385Y401771D03*
X1659448Y411614D03*
X1663385Y421457D03*
X1673228Y425394D03*
X1690100Y116000D03*
X1708075Y124025D03*
X1710000Y203500D03*
X1687008Y236614D03*
X1683071Y226771D03*
Y246457D03*
Y421457D03*
X1687008Y411614D03*
X1683071Y401771D03*
X1714100Y104500D03*
X1724600Y119500D03*
Y134500D03*
X1726100Y148780D03*
X1726600Y168500D03*
X1724922Y245500D03*
X1761100Y104500D03*
X1760500Y119500D03*
X1761600Y129500D03*
X1758600Y148780D03*
X1759000Y140000D03*
X1758600Y164280D03*
X1759000Y156000D03*
X1755000Y174000D03*
X1744500Y187500D03*
X1763000Y200500D03*
X1749000Y416000D03*
X1778000Y200500D03*
X1809600Y195000D03*
G54D13*
X59055Y236614D03*
Y411594D03*
X1673228Y236614D03*
Y411614D03*
G54D40*
X515009Y329000D03*
X511859D03*
D03*
X508709D03*
X511859Y322000D03*
X508709D03*
X511859D03*
X515009D03*
X1247275Y330000D03*
X1250425D03*
D03*
X1253575D03*
X1250425Y337000D03*
X1253575D03*
X1250425D03*
X1247275D03*
X1635195Y90940D03*
X1638345D03*
X1654615Y102380D03*
X1651465D03*
X1762454Y322905D03*
X1759304D03*
X1771833Y352305D03*
X1774983D03*
G54D31*
X230685Y115614D03*
Y142386D03*
X1501600Y109614D03*
Y136386D03*
G54D22*
X166785Y230000D03*
Y310000D03*
Y390000D03*
Y470000D03*
Y550000D03*
X243785Y230000D03*
Y310000D03*
Y390000D03*
Y470000D03*
Y550000D03*
X1488500Y230000D03*
Y310000D03*
Y390000D03*
Y470000D03*
Y550000D03*
X1565500Y230000D03*
Y310000D03*
Y390000D03*
Y470000D03*
Y550000D03*
G54D14*
X99149Y604098D03*
X1024887Y231919D03*
X1641531Y219808D03*
X1716930Y503124D03*
G54D50*
X674276Y315760D03*
Y319500D03*
Y323240D03*
X683724D03*
Y315760D03*
X1715376Y194760D03*
Y202240D03*
X1724824D03*
Y198500D03*
Y194760D03*
G54D41*
X554149Y116300D03*
Y249500D03*
X571865Y116300D03*
Y249500D03*
X1190419Y116300D03*
Y249500D03*
X1208135Y116300D03*
Y249500D03*
G54D32*
X208000Y118484D03*
X330500Y71984D03*
X326000D03*
X649500Y260484D03*
X653500Y329984D03*
X676500Y334984D03*
X680500D03*
X1037600Y191984D03*
X1499228Y71985D03*
X1503728D03*
X1524500Y101984D03*
X1628960Y111141D03*
X1627770Y130424D03*
X1645280Y130484D03*
X1638770Y130424D03*
X1631770D03*
X1641000Y204484D03*
X1629600Y195484D03*
X1649270Y130424D03*
X1690100Y135884D03*
X1700100Y124884D03*
X1707200Y163484D03*
X1721000Y147984D03*
Y163484D03*
X1764000Y147984D03*
Y163484D03*
X1746102Y331507D03*
X1852164Y424722D03*
X1837164D03*
X1847164D03*
X1842164D03*
G54D23*
X197691Y73000D03*
X176431D03*
X197691Y91000D03*
X176431D03*
X1574870Y67000D03*
Y85000D03*
X1596130Y67000D03*
Y85000D03*
G54D15*
X126986Y145500D03*
Y136500D03*
Y127500D03*
Y163500D03*
Y154500D03*
X139584Y145500D03*
Y136500D03*
Y127500D03*
Y163500D03*
Y154500D03*
X1592701Y149000D03*
X1605299D03*
Y140000D03*
X1592701D03*
Y131000D03*
X1605299D03*
Y122000D03*
X1592701D03*
X1605299Y158000D03*
X1592701D03*
G54D24*
X191885Y119000D03*
X200685Y115000D03*
Y123000D03*
X490384Y325500D03*
X499184Y329500D03*
Y321500D03*
X1263100Y329500D03*
X1271900Y333500D03*
X1263100Y337500D03*
X1539900Y112500D03*
X1531100Y108500D03*
Y116500D03*
X1762100Y241500D03*
Y248500D03*
X1771100Y241500D03*
Y248500D03*
X1779600Y241500D03*
Y248500D03*
G54D42*
X551430Y135300D03*
X557230D03*
Y142300D03*
X551430D03*
X557230Y149300D03*
X551430D03*
X557230Y268500D03*
X551430D03*
X557230Y282500D03*
X551430D03*
X557230Y275500D03*
X551430D03*
X574230Y135300D03*
X568430D03*
Y142300D03*
X574230D03*
X568430Y149300D03*
X574230D03*
X568430Y268500D03*
X574230D03*
X568430Y282500D03*
X574230D03*
X568430Y275500D03*
X574230D03*
X646900Y251500D03*
X641100D03*
X1114600Y300500D03*
X1120400D03*
X1193500Y135300D03*
X1187700D03*
Y142300D03*
X1193500D03*
Y149300D03*
X1187700D03*
X1193500Y268500D03*
X1187700D03*
X1193500Y282500D03*
X1187700D03*
X1193500Y275500D03*
X1187700D03*
X1204700Y135300D03*
X1210500D03*
Y142300D03*
X1204700D03*
Y149300D03*
X1210500D03*
X1204700Y268500D03*
X1210500D03*
X1204700Y282500D03*
X1210500D03*
X1204700Y275500D03*
X1210500D03*
X1628960Y101030D03*
X1634760D03*
X1628960Y95930D03*
X1634760D03*
G54D33*
X207874Y639095D03*
X1524409D03*
G54D51*
X668314Y570042D03*
X681498Y575042D03*
Y565042D03*
X668420Y598187D03*
X681604Y593187D03*
Y603187D03*
X1011017Y570042D03*
X997833Y575042D03*
Y565042D03*
X1011017Y598187D03*
X997833Y593187D03*
Y603187D03*
G54D60*
X1259296Y71900D03*
Y116300D03*
Y160700D03*
Y205100D03*
Y249500D03*
Y293900D03*
G54D25*
X190950Y106500D03*
X197250Y109059D03*
Y103941D03*
X1541150Y99500D03*
X1534850Y96941D03*
Y102059D03*
G54D70*
X1706100Y86500D03*
X1701100D03*
X1696100D03*
X1691100D03*
Y107300D03*
X1696100D03*
X1701100D03*
X1706100D03*
G54D16*
X134655Y120500D03*
X130915D03*
X1597630Y115000D03*
X1601370D03*
G54D34*
X240866Y15512D03*
X300866Y10197D03*
X1431417Y15512D03*
X1491417Y10197D03*
G54D52*
X690037Y188000D03*
X682163Y184260D03*
Y191740D03*
X705037Y193500D03*
X697163Y189760D03*
Y197240D03*
X1029063Y201500D03*
X1036937Y205240D03*
Y197760D03*
X1643037Y191000D03*
X1635163Y187260D03*
Y194740D03*
X1758437Y191000D03*
X1750563Y187260D03*
Y194740D03*
X1764563Y187260D03*
Y194740D03*
X1772437Y191000D03*
G54D43*
X559949Y116300D03*
X566065D03*
X559949Y249500D03*
X566065D03*
X1202335Y116300D03*
X1196219D03*
X1202335Y249500D03*
X1196219D03*
G54D61*
X1625426Y79800D03*
X1641174D03*
G54D44*
X561246Y155300D03*
Y287500D03*
X601516Y300000D03*
X663700Y256000D03*
X654200Y251500D03*
Y256000D03*
Y260500D03*
Y266000D03*
X663700Y251500D03*
X677616Y298500D03*
X659016Y322500D03*
X688516Y178500D03*
X727327Y300595D03*
X875116Y362000D03*
Y382000D03*
X1066616Y307500D03*
Y311500D03*
X1082616Y251500D03*
X1095616Y291500D03*
Y287500D03*
X1105116Y296000D03*
X1146516Y251500D03*
X1624786Y119140D03*
X1626516Y178000D03*
Y172500D03*
X1628516Y167500D03*
Y163500D03*
X1705016Y134500D03*
Y129500D03*
X1692516Y148000D03*
Y164500D03*
Y170000D03*
Y175500D03*
Y153500D03*
Y159000D03*
Y186500D03*
X1680516D03*
X1692516Y181000D03*
X1724216Y88000D03*
X1713216D03*
X1724216Y99000D03*
Y93500D03*
X1713216Y99000D03*
Y93500D03*
X1716016Y114500D03*
Y109500D03*
Y119500D03*
X1723016Y175000D03*
Y183500D03*
X1732016Y201500D03*
X1711116Y189500D03*
X1729016Y250000D03*
X1767516Y124500D03*
Y129500D03*
X1767016Y174000D03*
X1760016Y181500D03*
X1771796Y343970D03*
X1771916Y356300D03*
G54D26*
X192600Y130201D03*
Y142799D03*
X1539600Y123701D03*
Y136299D03*
G54D71*
X1732100Y104500D03*
Y109500D03*
Y114500D03*
Y119500D03*
Y124500D03*
Y129500D03*
Y134500D03*
X1752900Y114500D03*
Y109500D03*
Y104500D03*
Y134500D03*
Y129500D03*
Y124500D03*
Y119500D03*
G54D35*
X287402Y628465D03*
X263780Y659961D03*
X1468504Y628465D03*
X1444882Y659961D03*
G54D62*
X1620960Y111232D03*
Y108082D03*
X1624940Y111232D03*
Y108082D03*
X1662000Y108425D03*
Y111575D03*
G54D17*
X137303Y601693D03*
Y609567D03*
Y617441D03*
Y625315D03*
Y633189D03*
Y641063D03*
Y648937D03*
Y656811D03*
X163878Y601693D03*
X156004D03*
X145177D03*
X163878Y609567D03*
Y617441D03*
Y625315D03*
Y633189D03*
X156004Y609567D03*
Y617441D03*
Y625315D03*
Y633189D03*
X145177Y609567D03*
Y617441D03*
Y625315D03*
Y633189D03*
X163878Y641063D03*
Y648937D03*
Y656811D03*
X156004Y641063D03*
Y648937D03*
Y656811D03*
X145177Y641063D03*
Y648937D03*
Y656811D03*
X163878Y664685D03*
X156004D03*
X145177D03*
X192126Y633189D03*
Y625315D03*
Y617441D03*
Y656811D03*
Y648937D03*
Y664685D03*
X200000Y633189D03*
Y625315D03*
Y617441D03*
X215748Y633189D03*
Y625315D03*
Y617441D03*
X223622Y633189D03*
Y625315D03*
X215748Y656811D03*
Y648937D03*
X223622Y656811D03*
Y648937D03*
X200000Y656811D03*
Y648937D03*
X215748Y664685D03*
X223622D03*
X200000D03*
X250866Y20827D03*
Y10197D03*
X255906Y617441D03*
X248032D03*
X255906Y625315D03*
Y633189D03*
X248032D03*
Y625315D03*
X255906Y648937D03*
X248032D03*
X255906Y656811D03*
X248032D03*
X255906Y664685D03*
X248032D03*
X279646Y23012D03*
Y13012D03*
X284646Y18012D03*
X274646D03*
X284646Y8012D03*
X260866Y20827D03*
Y10197D03*
X279528Y617441D03*
X271654D03*
X279528Y625315D03*
Y633189D03*
X271654D03*
Y625315D03*
X279528Y648937D03*
X271654D03*
X279528Y656811D03*
X271654D03*
X279528Y664685D03*
X271654D03*
X289646Y23012D03*
Y13012D03*
X295276Y617441D03*
Y625315D03*
Y633189D03*
X303150D03*
Y625315D03*
Y648937D03*
X295276D03*
X303150Y656811D03*
X295276D03*
X303150Y664685D03*
X295276D03*
X1437008Y617441D03*
X1429134D03*
X1437008Y625315D03*
Y633189D03*
X1429134D03*
Y625315D03*
X1437008Y648937D03*
X1429134D03*
X1437008Y656811D03*
X1429134D03*
X1437008Y664685D03*
X1429134D03*
X1465197Y18012D03*
X1451417Y20827D03*
X1441417D03*
X1451417Y10197D03*
X1441417D03*
X1460630Y617441D03*
X1452756D03*
X1460630Y625315D03*
Y633189D03*
X1452756D03*
Y625315D03*
X1460630Y648937D03*
X1452756D03*
X1460630Y656811D03*
X1452756D03*
X1460630Y664685D03*
X1452756D03*
X1480197Y23012D03*
X1470197D03*
X1480197Y13012D03*
X1470197D03*
X1475197Y18012D03*
Y8012D03*
X1476378Y617441D03*
Y625315D03*
Y633189D03*
X1484252D03*
Y625315D03*
Y648937D03*
X1476378D03*
X1484252Y656811D03*
X1476378D03*
X1484252Y664685D03*
X1476378D03*
X1508661Y633189D03*
Y625315D03*
Y617441D03*
X1516535Y633189D03*
Y625315D03*
Y617441D03*
X1508661Y656811D03*
Y648937D03*
X1516535Y656811D03*
Y648937D03*
X1508661Y664685D03*
X1516535D03*
X1532283Y633189D03*
Y625315D03*
Y617441D03*
X1540157Y633189D03*
Y625315D03*
X1532283Y656811D03*
Y648937D03*
X1540157Y656811D03*
Y648937D03*
X1532283Y664685D03*
X1540157D03*
X1587107Y601693D03*
X1576280D03*
X1568406D03*
X1587107Y609567D03*
Y617441D03*
Y625315D03*
Y633189D03*
X1576280Y609567D03*
Y617441D03*
Y625315D03*
Y633189D03*
X1568406Y609567D03*
Y617441D03*
Y625315D03*
Y633189D03*
X1587107Y641063D03*
Y648937D03*
Y656811D03*
X1576280Y641063D03*
Y648937D03*
Y656811D03*
X1568406Y641063D03*
Y648937D03*
Y656811D03*
X1587107Y664685D03*
X1576280D03*
X1594981Y601693D03*
Y609567D03*
Y617441D03*
Y625315D03*
Y633189D03*
Y641063D03*
Y648937D03*
Y656811D03*
Y664685D03*
G54D53*
X802087Y145984D03*
X792087D03*
X802087Y135984D03*
X792087D03*
X802087Y180984D03*
X792087D03*
X802087Y170984D03*
X792087D03*
X802087Y200984D03*
X792087D03*
X802087Y230984D03*
X792087D03*
X802087Y220984D03*
X792087D03*
X802087Y265984D03*
X792087D03*
X802087Y255984D03*
X792087D03*
X822087Y145984D03*
X812087D03*
X822087Y135984D03*
X812087D03*
X822087Y180984D03*
X812087D03*
X822087Y170984D03*
X812087D03*
Y200984D03*
X822087Y230984D03*
X812087D03*
X822087Y220984D03*
X812087D03*
X822087Y265984D03*
X812087D03*
X822087Y255984D03*
X812087D03*
X920197Y145984D03*
X910197D03*
X920197Y135984D03*
X910197D03*
X920197Y180984D03*
X910197D03*
X920197Y170984D03*
X910197D03*
X920197Y200984D03*
X910197D03*
X920197Y230984D03*
X910197D03*
X920197Y220984D03*
X910197D03*
X920197Y265984D03*
X910197D03*
X920197Y255984D03*
X910197D03*
X940197Y145984D03*
X930197D03*
X940197Y135984D03*
X930197D03*
X940197Y180984D03*
X930197D03*
X940197Y170984D03*
X930197D03*
Y200984D03*
X940197Y230984D03*
X930197D03*
X940197Y220984D03*
X930197D03*
X940197Y265984D03*
X930197D03*
X940197Y255984D03*
X930197D03*
G54D80*
X1762533Y328965D03*
G54D90*
G01X-457143Y-1211429D02*
Y2242857D01*
X4308572D01*
Y-1211429D01*
X-457143D01*
G01X37000Y-995000D02*
Y-1070000D01*
X537000D01*
Y-995000D01*
X37000D01*
G01X49000Y-1060000D02*
Y-1065000D01*
G01X47543Y-1060000D02*
X50457D01*
G01X55367Y-1065000D02*
X52833D01*
Y-1060000D01*
X55367D01*
G01X54353Y-1062417D02*
X52833D01*
G01X57933Y-1060000D02*
Y-1065000D01*
X60467D01*
G01X64300Y-1065167D02*
X64173Y-1065083D01*
Y-1064917D01*
X64300Y-1064833D01*
X64427Y-1064917D01*
Y-1065083D01*
X64300Y-1065167D01*
G01Y-1062917D02*
X64173Y-1062833D01*
Y-1062667D01*
X64300Y-1062583D01*
X64427Y-1062667D01*
Y-1062833D01*
X64300Y-1062917D01*
G01X69083Y-1066667D02*
X68450Y-1065833D01*
X68133Y-1065000D01*
Y-1061667D01*
X68450Y-1060833D01*
X69083Y-1060000D01*
G01X74500D02*
X73993Y-1060167D01*
X73613Y-1060583D01*
X73360Y-1061083D01*
X73170Y-1061750D01*
X73107Y-1062500D01*
X73170Y-1063250D01*
X73360Y-1063917D01*
X73613Y-1064417D01*
X73993Y-1064833D01*
X74500Y-1065000D01*
X75007Y-1064833D01*
X75387Y-1064417D01*
X75640Y-1063917D01*
X75830Y-1063250D01*
X75893Y-1062500D01*
X75830Y-1061750D01*
X75640Y-1061083D01*
X75387Y-1060583D01*
X75007Y-1060167D01*
X74500Y-1060000D01*
G01X78207Y-1064000D02*
X78587Y-1064583D01*
X79093Y-1064917D01*
X79663Y-1065000D01*
X80170Y-1064917D01*
X80677Y-1064500D01*
X80993Y-1064000D01*
X81057Y-1063500D01*
X80930Y-1062917D01*
X80487Y-1062500D01*
X80043Y-1062333D01*
X79473D01*
G01X80043D02*
X80423Y-1062083D01*
X80740Y-1061667D01*
X80867Y-1061167D01*
X80740Y-1060667D01*
X80423Y-1060250D01*
X79853Y-1060000D01*
X79283Y-1060083D01*
X78713Y-1060417D01*
G01X85017Y-1066667D02*
X85650Y-1065833D01*
X85967Y-1065000D01*
Y-1061667D01*
X85650Y-1060833D01*
X85017Y-1060000D01*
G01X88407Y-1064000D02*
X88787Y-1064583D01*
X89293Y-1064917D01*
X89863Y-1065000D01*
X90370Y-1064917D01*
X90877Y-1064500D01*
X91193Y-1064000D01*
X91257Y-1063500D01*
X91130Y-1062917D01*
X90687Y-1062500D01*
X90243Y-1062333D01*
X89673D01*
G01X90243D02*
X90623Y-1062083D01*
X90940Y-1061667D01*
X91067Y-1061167D01*
X90940Y-1060667D01*
X90623Y-1060250D01*
X90053Y-1060000D01*
X89483Y-1060083D01*
X88913Y-1060417D01*
G01X93697Y-1060833D02*
X94077Y-1060333D01*
X94520Y-1060083D01*
X95027Y-1060000D01*
X95660Y-1060167D01*
X96103Y-1060583D01*
X96230Y-1061083D01*
X96167Y-1061583D01*
X95913Y-1062000D01*
X94647Y-1062833D01*
X94077Y-1063417D01*
X93697Y-1064250D01*
X93570Y-1065000D01*
X96230D01*
G01X99873D02*
X100000Y-1063917D01*
X100190Y-1063000D01*
X100443Y-1062167D01*
X100760Y-1061250D01*
X101267Y-1060000D01*
X98733D01*
G01X104277Y-1063333D02*
X105923D01*
G01X108997Y-1060833D02*
X109377Y-1060333D01*
X109820Y-1060083D01*
X110327Y-1060000D01*
X110960Y-1060167D01*
X111403Y-1060583D01*
X111530Y-1061083D01*
X111467Y-1061583D01*
X111213Y-1062000D01*
X109947Y-1062833D01*
X109377Y-1063417D01*
X108997Y-1064250D01*
X108870Y-1065000D01*
X111530D01*
G01X113907Y-1064000D02*
X114287Y-1064583D01*
X114793Y-1064917D01*
X115363Y-1065000D01*
X115870Y-1064917D01*
X116377Y-1064500D01*
X116693Y-1064000D01*
X116757Y-1063500D01*
X116630Y-1062917D01*
X116187Y-1062500D01*
X115743Y-1062333D01*
X115173D01*
G01X115743D02*
X116123Y-1062083D01*
X116440Y-1061667D01*
X116567Y-1061167D01*
X116440Y-1060667D01*
X116123Y-1060250D01*
X115553Y-1060000D01*
X114983Y-1060083D01*
X114413Y-1060417D01*
G01X121160Y-1065000D02*
Y-1060000D01*
X118817Y-1063583D01*
X121983D01*
G01X124107Y-1064250D02*
X124487Y-1064667D01*
X124930Y-1064917D01*
X125500Y-1065000D01*
X126070Y-1064833D01*
X126513Y-1064500D01*
X126830Y-1063917D01*
X126893Y-1063250D01*
X126767Y-1062583D01*
X126450Y-1062167D01*
X126007Y-1061833D01*
X125563Y-1061750D01*
X125120Y-1061833D01*
X124550Y-1062167D01*
X124740Y-1060000D01*
X126450D01*
G01X134497Y-1065000D02*
Y-1060000D01*
X136903D01*
G01X136017Y-1062417D02*
X134497D01*
G01X139217Y-1065000D02*
X140800Y-1060000D01*
X142383Y-1065000D01*
G01X141813Y-1063250D02*
X139787D01*
G01X144570Y-1065000D02*
X147230Y-1060000D01*
G01X144570D02*
X147230Y-1065000D01*
G01X151000Y-1065167D02*
X150873Y-1065083D01*
Y-1064917D01*
X151000Y-1064833D01*
X151127Y-1064917D01*
Y-1065083D01*
X151000Y-1065167D01*
G01Y-1062917D02*
X150873Y-1062833D01*
Y-1062667D01*
X151000Y-1062583D01*
X151127Y-1062667D01*
Y-1062833D01*
X151000Y-1062917D01*
G01X155783Y-1066667D02*
X155150Y-1065833D01*
X154833Y-1065000D01*
Y-1061667D01*
X155150Y-1060833D01*
X155783Y-1060000D01*
G01X161200D02*
X160693Y-1060167D01*
X160313Y-1060583D01*
X160060Y-1061083D01*
X159870Y-1061750D01*
X159807Y-1062500D01*
X159870Y-1063250D01*
X160060Y-1063917D01*
X160313Y-1064417D01*
X160693Y-1064833D01*
X161200Y-1065000D01*
X161707Y-1064833D01*
X162087Y-1064417D01*
X162340Y-1063917D01*
X162530Y-1063250D01*
X162593Y-1062500D01*
X162530Y-1061750D01*
X162340Y-1061083D01*
X162087Y-1060583D01*
X161707Y-1060167D01*
X161200Y-1060000D01*
G01X164907Y-1064000D02*
X165287Y-1064583D01*
X165793Y-1064917D01*
X166363Y-1065000D01*
X166870Y-1064917D01*
X167377Y-1064500D01*
X167693Y-1064000D01*
X167757Y-1063500D01*
X167630Y-1062917D01*
X167187Y-1062500D01*
X166743Y-1062333D01*
X166173D01*
G01X166743D02*
X167123Y-1062083D01*
X167440Y-1061667D01*
X167567Y-1061167D01*
X167440Y-1060667D01*
X167123Y-1060250D01*
X166553Y-1060000D01*
X165983Y-1060083D01*
X165413Y-1060417D01*
G01X171717Y-1066667D02*
X172350Y-1065833D01*
X172667Y-1065000D01*
Y-1061667D01*
X172350Y-1060833D01*
X171717Y-1060000D01*
G01X175107Y-1064000D02*
X175487Y-1064583D01*
X175993Y-1064917D01*
X176563Y-1065000D01*
X177070Y-1064917D01*
X177577Y-1064500D01*
X177893Y-1064000D01*
X177957Y-1063500D01*
X177830Y-1062917D01*
X177387Y-1062500D01*
X176943Y-1062333D01*
X176373D01*
G01X176943D02*
X177323Y-1062083D01*
X177640Y-1061667D01*
X177767Y-1061167D01*
X177640Y-1060667D01*
X177323Y-1060250D01*
X176753Y-1060000D01*
X176183Y-1060083D01*
X175613Y-1060417D01*
G01X180523Y-1064417D02*
X180967Y-1064833D01*
X181473Y-1065000D01*
X181980Y-1064833D01*
X182423Y-1064333D01*
X182740Y-1063583D01*
X182867Y-1062833D01*
Y-1061917D01*
X182740Y-1061167D01*
X182423Y-1060500D01*
X182043Y-1060167D01*
X181600Y-1060000D01*
X181093Y-1060167D01*
X180713Y-1060500D01*
X180460Y-1061000D01*
X180333Y-1061667D01*
X180460Y-1062250D01*
X180777Y-1062833D01*
X181157Y-1063167D01*
X181600Y-1063250D01*
X182107Y-1063083D01*
X182487Y-1062667D01*
X182867Y-1061917D01*
G01X186573Y-1065000D02*
X186700Y-1063917D01*
X186890Y-1063000D01*
X187143Y-1062167D01*
X187460Y-1061250D01*
X187967Y-1060000D01*
X185433D01*
G01X190977Y-1063333D02*
X192623D01*
G01X195507Y-1064000D02*
X195887Y-1064583D01*
X196393Y-1064917D01*
X196963Y-1065000D01*
X197470Y-1064917D01*
X197977Y-1064500D01*
X198293Y-1064000D01*
X198357Y-1063500D01*
X198230Y-1062917D01*
X197787Y-1062500D01*
X197343Y-1062333D01*
X196773D01*
G01X197343D02*
X197723Y-1062083D01*
X198040Y-1061667D01*
X198167Y-1061167D01*
X198040Y-1060667D01*
X197723Y-1060250D01*
X197153Y-1060000D01*
X196583Y-1060083D01*
X196013Y-1060417D01*
G01X200797Y-1062917D02*
X201240Y-1062333D01*
X201620Y-1062000D01*
X202127Y-1061833D01*
X202570Y-1062000D01*
X202887Y-1062333D01*
X203140Y-1062833D01*
X203203Y-1063417D01*
X203140Y-1063917D01*
X202887Y-1064417D01*
X202507Y-1064833D01*
X202063Y-1065000D01*
X201557Y-1064833D01*
X201113Y-1064333D01*
X200860Y-1063583D01*
X200797Y-1062750D01*
X200923Y-1061667D01*
X201113Y-1061083D01*
X201430Y-1060500D01*
X201873Y-1060083D01*
X202317Y-1060000D01*
X202760Y-1060167D01*
X203077Y-1060583D01*
G01X207100Y-1065000D02*
Y-1060000D01*
X206340Y-1061000D01*
G01Y-1065000D02*
X207860D01*
G01X212960D02*
Y-1060000D01*
X210617Y-1063583D01*
X213783D01*
G01X232000Y-995000D02*
Y-1070000D01*
G01Y-1045000D02*
X335000D01*
Y-1020000D01*
G01X232000D02*
X335000D01*
G01X337000Y-995000D02*
Y-1070000D01*
G01X335000Y-995000D02*
Y-1070000D01*
G01X342507Y-1055000D02*
Y-1050000D01*
X343773D01*
X344280Y-1050250D01*
X344660Y-1050583D01*
X344977Y-1051083D01*
X345230Y-1051667D01*
X345293Y-1052500D01*
X345230Y-1053333D01*
X344977Y-1053917D01*
X344660Y-1054417D01*
X344280Y-1054750D01*
X343773Y-1055000D01*
X342507D01*
G01X347417D02*
X349000Y-1050000D01*
X350583Y-1055000D01*
G01X350013Y-1053250D02*
X347987D01*
G01X354100Y-1050000D02*
Y-1055000D01*
G01X352643Y-1050000D02*
X355557D01*
G01X360467Y-1055000D02*
X357933D01*
Y-1050000D01*
X360467D01*
G01X359453Y-1052417D02*
X357933D01*
G01X364300Y-1055167D02*
X364173Y-1055083D01*
Y-1054917D01*
X364300Y-1054833D01*
X364427Y-1054917D01*
Y-1055083D01*
X364300Y-1055167D01*
G01Y-1052917D02*
X364173Y-1052833D01*
Y-1052667D01*
X364300Y-1052583D01*
X364427Y-1052667D01*
Y-1052833D01*
X364300Y-1052917D01*
G01X337000Y-1045000D02*
X537000D01*
G01X342633Y-1030000D02*
Y-1025000D01*
X344153D01*
X344660Y-1025250D01*
X345040Y-1025833D01*
X345167Y-1026500D01*
X345040Y-1027167D01*
X344723Y-1027667D01*
X344153Y-1027917D01*
X342633D01*
G01X347860Y-1030167D02*
X350140Y-1025000D01*
G01X352643Y-1030000D02*
Y-1025000D01*
X355557Y-1030000D01*
Y-1025000D01*
G01X359200Y-1030167D02*
X359073Y-1030083D01*
Y-1029917D01*
X359200Y-1029833D01*
X359327Y-1029917D01*
Y-1030083D01*
X359200Y-1030167D01*
G01Y-1027917D02*
X359073Y-1027833D01*
Y-1027667D01*
X359200Y-1027583D01*
X359327Y-1027667D01*
Y-1027833D01*
X359200Y-1027917D01*
G01X342633Y-1005000D02*
Y-1000000D01*
X344153D01*
X344660Y-1000250D01*
X345040Y-1000833D01*
X345167Y-1001500D01*
X345040Y-1002167D01*
X344723Y-1002667D01*
X344153Y-1002917D01*
X342633D01*
G01X347733Y-1005000D02*
Y-1000000D01*
X349317D01*
X349823Y-1000250D01*
X350140Y-1000583D01*
X350267Y-1001250D01*
X350140Y-1001917D01*
X349760Y-1002333D01*
X349317Y-1002583D01*
X347733D01*
G01X349317D02*
X350267Y-1005000D01*
G01X354100D02*
X353593Y-1004917D01*
X353150Y-1004583D01*
X352770Y-1004083D01*
X352517Y-1003500D01*
X352390Y-1002833D01*
Y-1002167D01*
X352517Y-1001500D01*
X352770Y-1000917D01*
X353150Y-1000417D01*
X353593Y-1000083D01*
X354100Y-1000000D01*
X354607Y-1000083D01*
X355050Y-1000417D01*
X355430Y-1000917D01*
X355683Y-1001500D01*
X355810Y-1002167D01*
Y-1002833D01*
X355683Y-1003500D01*
X355430Y-1004083D01*
X355050Y-1004583D01*
X354607Y-1004917D01*
X354100Y-1005000D01*
G01X357933Y-1004000D02*
X358250Y-1004500D01*
X358630Y-1004833D01*
X359073Y-1005000D01*
X359580Y-1004833D01*
X359960Y-1004500D01*
X360340Y-1004000D01*
X360467Y-1003333D01*
Y-1000000D01*
G01X365567Y-1005000D02*
X363033D01*
Y-1000000D01*
X365567D01*
G01X364553Y-1002417D02*
X363033D01*
G01X370793Y-1000417D02*
X370413Y-1000167D01*
X369970Y-1000000D01*
X369463D01*
X368893Y-1000250D01*
X368450Y-1000667D01*
X368133Y-1001167D01*
X367880Y-1002000D01*
X367817Y-1002750D01*
X367943Y-1003500D01*
X368133Y-1004000D01*
X368513Y-1004500D01*
X368957Y-1004833D01*
X369400Y-1005000D01*
X369843D01*
X370287Y-1004833D01*
X370667Y-1004583D01*
X370983Y-1004250D01*
G01X374500Y-1000000D02*
Y-1005000D01*
G01X373043Y-1000000D02*
X375957D01*
G01X379600Y-1005167D02*
X379473Y-1005083D01*
Y-1004917D01*
X379600Y-1004833D01*
X379727Y-1004917D01*
Y-1005083D01*
X379600Y-1005167D01*
G01Y-1002917D02*
X379473Y-1002833D01*
Y-1002667D01*
X379600Y-1002583D01*
X379727Y-1002667D01*
Y-1002833D01*
X379600Y-1002917D01*
G01X337000Y-1020000D02*
X537000D01*
G01X452000Y-1045000D02*
Y-1070000D01*
G01X454633Y-1047500D02*
Y-1052500D01*
X457167D01*
G01X460240Y-1047500D02*
X461760D01*
G01X461000D02*
Y-1052500D01*
G01X460240D02*
X461760D01*
G01X466607Y-1049833D02*
X466860Y-1049583D01*
X467050Y-1049167D01*
X467177Y-1048583D01*
X467050Y-1048083D01*
X466797Y-1047750D01*
X466353Y-1047500D01*
X464643D01*
Y-1052500D01*
X466733D01*
X467177Y-1052167D01*
X467430Y-1051667D01*
X467557Y-1051083D01*
X467430Y-1050500D01*
X467050Y-1050000D01*
X466607Y-1049833D01*
X464643D01*
G01X471200Y-1052667D02*
X471073Y-1052583D01*
Y-1052417D01*
X471200Y-1052333D01*
X471327Y-1052417D01*
Y-1052583D01*
X471200Y-1052667D01*
G01Y-1050417D02*
X471073Y-1050333D01*
Y-1050167D01*
X471200Y-1050083D01*
X471327Y-1050167D01*
Y-1050333D01*
X471200Y-1050417D01*
G01X495000Y-1045000D02*
Y-1070000D01*
G01X498900Y-1047500D02*
Y-1052500D01*
G01X497443Y-1047500D02*
X500357D01*
G01X504000Y-1052500D02*
X503620Y-1052417D01*
X503240Y-1052083D01*
X502987Y-1051500D01*
X502860Y-1050833D01*
X502987Y-1050167D01*
X503240Y-1049583D01*
X503620Y-1049250D01*
X504000Y-1049167D01*
X504380Y-1049250D01*
X504760Y-1049583D01*
X505013Y-1050167D01*
X505077Y-1050833D01*
X505013Y-1051500D01*
X504760Y-1052083D01*
X504380Y-1052417D01*
X504000Y-1052500D01*
G01X509100D02*
X508720Y-1052417D01*
X508340Y-1052083D01*
X508087Y-1051500D01*
X507960Y-1050833D01*
X508087Y-1050167D01*
X508340Y-1049583D01*
X508720Y-1049250D01*
X509100Y-1049167D01*
X509480Y-1049250D01*
X509860Y-1049583D01*
X510113Y-1050167D01*
X510177Y-1050833D01*
X510113Y-1051500D01*
X509860Y-1052083D01*
X509480Y-1052417D01*
X509100Y-1052500D01*
G01X514200D02*
Y-1047500D01*
G01X519300Y-1052667D02*
X519173Y-1052583D01*
Y-1052417D01*
X519300Y-1052333D01*
X519427Y-1052417D01*
Y-1052583D01*
X519300Y-1052667D01*
G01Y-1050417D02*
X519173Y-1050333D01*
Y-1050167D01*
X519300Y-1050083D01*
X519427Y-1050167D01*
Y-1050333D01*
X519300Y-1050417D01*
G01X495000Y-1020000D02*
Y-1045000D01*
G01X497633Y-1027500D02*
Y-1022500D01*
X499217D01*
X499723Y-1022750D01*
X500040Y-1023083D01*
X500167Y-1023750D01*
X500040Y-1024417D01*
X499660Y-1024833D01*
X499217Y-1025083D01*
X497633D01*
G01X499217D02*
X500167Y-1027500D01*
G01X505267D02*
X502733D01*
Y-1022500D01*
X505267D01*
G01X504253Y-1024917D02*
X502733D01*
G01X507517Y-1022500D02*
X509100Y-1027500D01*
X510683Y-1022500D01*
G01X514200Y-1027667D02*
X514073Y-1027583D01*
Y-1027417D01*
X514200Y-1027333D01*
X514327Y-1027417D01*
Y-1027583D01*
X514200Y-1027667D01*
G01Y-1025417D02*
X514073Y-1025333D01*
Y-1025167D01*
X514200Y-1025083D01*
X514327Y-1025167D01*
Y-1025333D01*
X514200Y-1025417D01*
G01X503013Y-1073167D02*
X503120Y-1073042D01*
X503200Y-1072833D01*
X503253Y-1072542D01*
X503200Y-1072292D01*
X503093Y-1072125D01*
X502907Y-1072000D01*
X502187D01*
Y-1074500D01*
X503067D01*
X503253Y-1074333D01*
X503360Y-1074083D01*
X503413Y-1073792D01*
X503360Y-1073500D01*
X503200Y-1073250D01*
X503013Y-1073167D01*
X502187D01*
G01X505480Y-1074500D02*
Y-1072833D01*
G01Y-1073125D02*
X505373Y-1072958D01*
X505213Y-1072875D01*
X505027Y-1072833D01*
X504840Y-1072917D01*
X504680Y-1073083D01*
X504573Y-1073333D01*
X504520Y-1073667D01*
X504573Y-1074000D01*
X504680Y-1074250D01*
X504840Y-1074417D01*
X505027Y-1074500D01*
X505213Y-1074458D01*
X505373Y-1074333D01*
X505480Y-1074167D01*
G01X506800Y-1074208D02*
X506933Y-1074375D01*
X507120Y-1074500D01*
X507280D01*
X507440Y-1074417D01*
X507547Y-1074292D01*
X507600Y-1074125D01*
X507573Y-1073875D01*
X507467Y-1073750D01*
X506987Y-1073500D01*
X506880Y-1073208D01*
X506933Y-1073000D01*
X507040Y-1072875D01*
X507200Y-1072833D01*
X507360Y-1072875D01*
X507520Y-1073000D01*
G01X509000Y-1073375D02*
X509853D01*
X509773Y-1073083D01*
X509640Y-1072917D01*
X509453Y-1072833D01*
X509267Y-1072875D01*
X509107Y-1073000D01*
X509000Y-1073292D01*
X508947Y-1073542D01*
Y-1073792D01*
X509000Y-1074042D01*
X509133Y-1074292D01*
X509293Y-1074458D01*
X509480Y-1074500D01*
X509667Y-1074417D01*
X509853Y-1074167D01*
G01X511120Y-1074500D02*
Y-1072000D01*
G01Y-1073250D02*
X511253Y-1073000D01*
X511413Y-1072875D01*
X511573Y-1072833D01*
X511813Y-1072917D01*
X511973Y-1073083D01*
X512080Y-1073375D01*
Y-1073708D01*
X512027Y-1074042D01*
X511920Y-1074292D01*
X511733Y-1074458D01*
X511573Y-1074500D01*
X511413Y-1074458D01*
X511253Y-1074333D01*
X511120Y-1074125D01*
G01X513800Y-1074500D02*
X513640Y-1074458D01*
X513480Y-1074292D01*
X513373Y-1074000D01*
X513320Y-1073667D01*
X513373Y-1073333D01*
X513480Y-1073042D01*
X513640Y-1072875D01*
X513800Y-1072833D01*
X513960Y-1072875D01*
X514120Y-1073042D01*
X514227Y-1073333D01*
X514253Y-1073667D01*
X514227Y-1074000D01*
X514120Y-1074292D01*
X513960Y-1074458D01*
X513800Y-1074500D01*
G01X516480D02*
Y-1072833D01*
G01Y-1073125D02*
X516373Y-1072958D01*
X516213Y-1072875D01*
X516027Y-1072833D01*
X515840Y-1072917D01*
X515680Y-1073083D01*
X515573Y-1073333D01*
X515520Y-1073667D01*
X515573Y-1074000D01*
X515680Y-1074250D01*
X515840Y-1074417D01*
X516027Y-1074500D01*
X516213Y-1074458D01*
X516373Y-1074333D01*
X516480Y-1074167D01*
G01X517827Y-1074500D02*
Y-1072833D01*
G01Y-1073167D02*
X517960Y-1073000D01*
X518093Y-1072875D01*
X518280Y-1072833D01*
X518413Y-1072875D01*
X518573Y-1073000D01*
G01X520880Y-1072000D02*
Y-1074500D01*
G01Y-1074125D02*
X520773Y-1074333D01*
X520613Y-1074458D01*
X520427Y-1074500D01*
X520213Y-1074417D01*
X520053Y-1074208D01*
X519947Y-1073958D01*
X519920Y-1073667D01*
X519947Y-1073375D01*
X520053Y-1073125D01*
X520213Y-1072917D01*
X520427Y-1072833D01*
X520613Y-1072875D01*
X520747Y-1072958D01*
X520880Y-1073125D01*
G01X524267Y-1074500D02*
Y-1072000D01*
X524933D01*
X525147Y-1072125D01*
X525280Y-1072292D01*
X525333Y-1072625D01*
X525280Y-1072958D01*
X525120Y-1073167D01*
X524933Y-1073292D01*
X524267D01*
G01X524933D02*
X525333Y-1074500D01*
G01X526600Y-1073375D02*
X527453D01*
X527373Y-1073083D01*
X527240Y-1072917D01*
X527053Y-1072833D01*
X526867Y-1072875D01*
X526707Y-1073000D01*
X526600Y-1073292D01*
X526547Y-1073542D01*
Y-1073792D01*
X526600Y-1074042D01*
X526733Y-1074292D01*
X526893Y-1074458D01*
X527080Y-1074500D01*
X527267Y-1074417D01*
X527453Y-1074167D01*
G01X528720Y-1072833D02*
X529200Y-1074500D01*
X529680Y-1072833D01*
G01X531400Y-1074583D02*
X531347Y-1074542D01*
Y-1074458D01*
X531400Y-1074417D01*
X531453Y-1074458D01*
Y-1074542D01*
X531400Y-1074583D01*
G01X533600Y-1074500D02*
X533787Y-1074458D01*
X534000Y-1074333D01*
X534133Y-1074125D01*
X534187Y-1073833D01*
X534133Y-1073542D01*
X533973Y-1073292D01*
X533733Y-1073167D01*
X533467D01*
X533307Y-1073083D01*
X533173Y-1072875D01*
X533120Y-1072583D01*
X533200Y-1072292D01*
X533387Y-1072083D01*
X533600Y-1072000D01*
X533813Y-1072083D01*
X534000Y-1072292D01*
X534080Y-1072583D01*
X534027Y-1072875D01*
X533893Y-1073083D01*
X533733Y-1073167D01*
X533467D01*
X533227Y-1073292D01*
X533067Y-1073542D01*
X533013Y-1073833D01*
X533067Y-1074125D01*
X533200Y-1074333D01*
X533413Y-1074458D01*
X533600Y-1074500D01*
G01X536013Y-1073167D02*
X536120Y-1073042D01*
X536200Y-1072833D01*
X536253Y-1072542D01*
X536200Y-1072292D01*
X536093Y-1072125D01*
X535907Y-1072000D01*
X535187D01*
Y-1074500D01*
X536067D01*
X536253Y-1074333D01*
X536360Y-1074083D01*
X536413Y-1073792D01*
X536360Y-1073500D01*
X536200Y-1073250D01*
X536013Y-1073167D01*
X535187D01*
G01X-457143Y-1211429D02*
Y2242857D01*
X4308572D01*
Y-1211429D01*
X-457143D01*
G01X71650Y-1024800D02*
X69130Y-1024383D01*
X66925Y-1022717D01*
X65035Y-1020217D01*
X63775Y-1017300D01*
X63145Y-1013967D01*
Y-1010633D01*
X63775Y-1007300D01*
X65035Y-1004383D01*
X66925Y-1001884D01*
X69130Y-1000217D01*
X71650Y-999800D01*
X74170Y-1000217D01*
X76375Y-1001884D01*
X78265Y-1004383D01*
X79525Y-1007300D01*
X80155Y-1010633D01*
Y-1013967D01*
X79525Y-1017300D01*
X78265Y-1020217D01*
X76375Y-1022717D01*
X74170Y-1024383D01*
X71650Y-1024800D01*
G01X74170Y-1018133D02*
X77950Y-1024800D01*
G01X91495Y-1008134D02*
Y-1019800D01*
X92755Y-1022717D01*
X94645Y-1024383D01*
X96850Y-1024800D01*
X99055Y-1024383D01*
X100945Y-1022717D01*
X102205Y-1019800D01*
G01Y-1024800D02*
Y-1008134D01*
G01X127720Y-1024800D02*
Y-1008134D01*
G01Y-1011050D02*
X126460Y-1009384D01*
X124570Y-1008550D01*
X122365Y-1008134D01*
X120160Y-1008967D01*
X118270Y-1010633D01*
X117010Y-1013134D01*
X116380Y-1016467D01*
X117010Y-1019800D01*
X118270Y-1022301D01*
X120160Y-1023967D01*
X122365Y-1024800D01*
X124570Y-1024383D01*
X126460Y-1023134D01*
X127720Y-1021467D01*
G01X141895Y-1024800D02*
Y-1008134D01*
G01Y-1012300D02*
X143155Y-1010217D01*
X145045Y-1008550D01*
X147565Y-1008134D01*
X149770Y-1008550D01*
X151660Y-1010217D01*
X152605Y-1013134D01*
Y-1024800D01*
G01X172450Y-999800D02*
Y-1024800D01*
G01X168040Y-1008134D02*
X176860D01*
G01X203320Y-1024800D02*
Y-1008134D01*
G01Y-1011050D02*
X202060Y-1009384D01*
X200170Y-1008550D01*
X197965Y-1008134D01*
X195760Y-1008967D01*
X193870Y-1010633D01*
X192610Y-1013134D01*
X191980Y-1016467D01*
X192610Y-1019800D01*
X193870Y-1022301D01*
X195760Y-1023967D01*
X197965Y-1024800D01*
X200170Y-1024383D01*
X202060Y-1023134D01*
X203320Y-1021467D01*
G01X49820Y-1042350D02*
X51387D01*
Y-1044240D01*
X50917Y-1044870D01*
X50368Y-1045290D01*
X49585Y-1045500D01*
X48802Y-1045290D01*
X48253Y-1044870D01*
X47783Y-1044240D01*
X47470Y-1043505D01*
X47313Y-1042665D01*
Y-1041930D01*
X47470Y-1041300D01*
X47783Y-1040565D01*
X48253Y-1039935D01*
X48723Y-1039515D01*
X49350Y-1039200D01*
X49898D01*
X50525Y-1039410D01*
X50995Y-1039830D01*
G01X53927Y-1039200D02*
Y-1043715D01*
X54240Y-1044660D01*
X54867Y-1045290D01*
X55650Y-1045500D01*
X56433Y-1045290D01*
X57060Y-1044660D01*
X57373Y-1043715D01*
Y-1039200D01*
G01X61010D02*
X62890D01*
G01X61950D02*
Y-1045500D01*
G01X61010D02*
X62890D01*
G01X66605Y-1044660D02*
X67232Y-1045185D01*
X67937Y-1045500D01*
X68563D01*
X69190Y-1045185D01*
X69660Y-1044660D01*
X69895Y-1043925D01*
X69738Y-1043190D01*
X69347Y-1042560D01*
X68642Y-1042140D01*
X67702Y-1041930D01*
X67153Y-1041510D01*
X66918Y-1040775D01*
X67075Y-1040040D01*
X67467Y-1039515D01*
X68015Y-1039200D01*
X68563D01*
X69112Y-1039410D01*
X69582Y-1039935D01*
G01X72905Y-1045500D02*
Y-1039200D01*
G01X76195D02*
Y-1045500D01*
G01Y-1042350D02*
X72905D01*
G01X78892Y-1045500D02*
X80850Y-1039200D01*
X82808Y-1045500D01*
G01X82103Y-1043295D02*
X79597D01*
G01X85348Y-1045500D02*
Y-1039200D01*
X88952Y-1045500D01*
Y-1039200D01*
G01X98027Y-1045500D02*
Y-1039200D01*
X99593D01*
X100220Y-1039515D01*
X100690Y-1039935D01*
X101082Y-1040565D01*
X101395Y-1041300D01*
X101473Y-1042350D01*
X101395Y-1043400D01*
X101082Y-1044135D01*
X100690Y-1044765D01*
X100220Y-1045185D01*
X99593Y-1045500D01*
X98027D01*
G01X105110Y-1039200D02*
X106990D01*
G01X106050D02*
Y-1045500D01*
G01X105110D02*
X106990D01*
G01X110705Y-1044660D02*
X111332Y-1045185D01*
X112037Y-1045500D01*
X112663D01*
X113290Y-1045185D01*
X113760Y-1044660D01*
X113995Y-1043925D01*
X113838Y-1043190D01*
X113447Y-1042560D01*
X112742Y-1042140D01*
X111802Y-1041930D01*
X111253Y-1041510D01*
X111018Y-1040775D01*
X111175Y-1040040D01*
X111567Y-1039515D01*
X112115Y-1039200D01*
X112663D01*
X113212Y-1039410D01*
X113682Y-1039935D01*
G01X118650Y-1039200D02*
Y-1045500D01*
G01X116848Y-1039200D02*
X120452D01*
G01X124950Y-1045710D02*
X124793Y-1045605D01*
Y-1045395D01*
X124950Y-1045290D01*
X125107Y-1045395D01*
Y-1045605D01*
X124950Y-1045710D01*
G01X131093Y-1046655D02*
X131407Y-1045290D01*
G01X137550Y-1039200D02*
Y-1045500D01*
G01X135748Y-1039200D02*
X139352D01*
G01X141892Y-1045500D02*
X143850Y-1039200D01*
X145808Y-1045500D01*
G01X145103Y-1043295D02*
X142597D01*
G01X150150Y-1045500D02*
X149523Y-1045395D01*
X148975Y-1044975D01*
X148505Y-1044345D01*
X148192Y-1043610D01*
X148035Y-1042770D01*
Y-1041930D01*
X148192Y-1041090D01*
X148505Y-1040355D01*
X148975Y-1039725D01*
X149523Y-1039305D01*
X150150Y-1039200D01*
X150777Y-1039305D01*
X151325Y-1039725D01*
X151795Y-1040355D01*
X152108Y-1041090D01*
X152265Y-1041930D01*
Y-1042770D01*
X152108Y-1043610D01*
X151795Y-1044345D01*
X151325Y-1044975D01*
X150777Y-1045395D01*
X150150Y-1045500D01*
G01X156450D02*
Y-1042665D01*
X154883Y-1039200D01*
G01X158017D02*
X156450Y-1042665D01*
G01X161027Y-1039200D02*
Y-1043715D01*
X161340Y-1044660D01*
X161967Y-1045290D01*
X162750Y-1045500D01*
X163533Y-1045290D01*
X164160Y-1044660D01*
X164473Y-1043715D01*
Y-1039200D01*
G01X167092Y-1045500D02*
X169050Y-1039200D01*
X171008Y-1045500D01*
G01X170303Y-1043295D02*
X167797D01*
G01X173548Y-1045500D02*
Y-1039200D01*
X177152Y-1045500D01*
Y-1039200D01*
G01X51073Y-1049725D02*
X50603Y-1049410D01*
X50055Y-1049200D01*
X49428D01*
X48723Y-1049515D01*
X48175Y-1050040D01*
X47783Y-1050670D01*
X47470Y-1051720D01*
X47392Y-1052665D01*
X47548Y-1053610D01*
X47783Y-1054240D01*
X48253Y-1054870D01*
X48802Y-1055290D01*
X49350Y-1055500D01*
X49898D01*
X50447Y-1055290D01*
X50917Y-1054975D01*
X51308Y-1054555D01*
G01X54710Y-1049200D02*
X56590D01*
G01X55650D02*
Y-1055500D01*
G01X54710D02*
X56590D01*
G01X61950Y-1049200D02*
Y-1055500D01*
G01X60148Y-1049200D02*
X63752D01*
G01X68250Y-1055500D02*
Y-1052665D01*
X66683Y-1049200D01*
G01X69817D02*
X68250Y-1052665D01*
G01X79127Y-1054240D02*
X79597Y-1054975D01*
X80223Y-1055395D01*
X80928Y-1055500D01*
X81555Y-1055395D01*
X82182Y-1054870D01*
X82573Y-1054240D01*
X82652Y-1053610D01*
X82495Y-1052875D01*
X81947Y-1052350D01*
X81398Y-1052140D01*
X80693D01*
G01X81398D02*
X81868Y-1051825D01*
X82260Y-1051300D01*
X82417Y-1050670D01*
X82260Y-1050040D01*
X81868Y-1049515D01*
X81163Y-1049200D01*
X80458Y-1049305D01*
X79753Y-1049725D01*
G01X85427Y-1054240D02*
X85897Y-1054975D01*
X86523Y-1055395D01*
X87228Y-1055500D01*
X87855Y-1055395D01*
X88482Y-1054870D01*
X88873Y-1054240D01*
X88952Y-1053610D01*
X88795Y-1052875D01*
X88247Y-1052350D01*
X87698Y-1052140D01*
X86993D01*
G01X87698D02*
X88168Y-1051825D01*
X88560Y-1051300D01*
X88717Y-1050670D01*
X88560Y-1050040D01*
X88168Y-1049515D01*
X87463Y-1049200D01*
X86758Y-1049305D01*
X86053Y-1049725D01*
G01X91727Y-1054240D02*
X92197Y-1054975D01*
X92823Y-1055395D01*
X93528Y-1055500D01*
X94155Y-1055395D01*
X94782Y-1054870D01*
X95173Y-1054240D01*
X95252Y-1053610D01*
X95095Y-1052875D01*
X94547Y-1052350D01*
X93998Y-1052140D01*
X93293D01*
G01X93998D02*
X94468Y-1051825D01*
X94860Y-1051300D01*
X95017Y-1050670D01*
X94860Y-1050040D01*
X94468Y-1049515D01*
X93763Y-1049200D01*
X93058Y-1049305D01*
X92353Y-1049725D01*
G01X99593Y-1055500D02*
X99750Y-1054135D01*
X99985Y-1052980D01*
X100298Y-1051930D01*
X100690Y-1050775D01*
X101317Y-1049200D01*
X98183D01*
G01X105893Y-1055500D02*
X106050Y-1054135D01*
X106285Y-1052980D01*
X106598Y-1051930D01*
X106990Y-1050775D01*
X107617Y-1049200D01*
X104483D01*
G01X112193Y-1056655D02*
X112507Y-1055290D01*
G01X118650Y-1049200D02*
Y-1055500D01*
G01X116848Y-1049200D02*
X120452D01*
G01X122992Y-1055500D02*
X124950Y-1049200D01*
X126908Y-1055500D01*
G01X126203Y-1053295D02*
X123697D01*
G01X130310Y-1049200D02*
X132190D01*
G01X131250D02*
Y-1055500D01*
G01X130310D02*
X132190D01*
G01X135200Y-1049200D02*
X136297Y-1055500D01*
X137550Y-1049200D01*
X138803Y-1055500D01*
X139900Y-1049200D01*
G01X141892Y-1055500D02*
X143850Y-1049200D01*
X145808Y-1055500D01*
G01X145103Y-1053295D02*
X142597D01*
G01X148348Y-1055500D02*
Y-1049200D01*
X151952Y-1055500D01*
Y-1049200D01*
G01X162358Y-1057600D02*
X161575Y-1056550D01*
X161183Y-1055500D01*
Y-1051300D01*
X161575Y-1050250D01*
X162358Y-1049200D01*
G01X173783Y-1055500D02*
Y-1049200D01*
X175742D01*
X176368Y-1049515D01*
X176760Y-1049935D01*
X176917Y-1050775D01*
X176760Y-1051615D01*
X176290Y-1052140D01*
X175742Y-1052455D01*
X173783D01*
G01X175742D02*
X176917Y-1055500D01*
G01X181650Y-1055710D02*
X181493Y-1055605D01*
Y-1055395D01*
X181650Y-1055290D01*
X181807Y-1055395D01*
Y-1055605D01*
X181650Y-1055710D01*
G01X187950Y-1055500D02*
X187323Y-1055395D01*
X186775Y-1054975D01*
X186305Y-1054345D01*
X185992Y-1053610D01*
X185835Y-1052770D01*
Y-1051930D01*
X185992Y-1051090D01*
X186305Y-1050355D01*
X186775Y-1049725D01*
X187323Y-1049305D01*
X187950Y-1049200D01*
X188577Y-1049305D01*
X189125Y-1049725D01*
X189595Y-1050355D01*
X189908Y-1051090D01*
X190065Y-1051930D01*
Y-1052770D01*
X189908Y-1053610D01*
X189595Y-1054345D01*
X189125Y-1054975D01*
X188577Y-1055395D01*
X187950Y-1055500D01*
G01X194250Y-1055710D02*
X194093Y-1055605D01*
Y-1055395D01*
X194250Y-1055290D01*
X194407Y-1055395D01*
Y-1055605D01*
X194250Y-1055710D01*
G01X202273Y-1049725D02*
X201803Y-1049410D01*
X201255Y-1049200D01*
X200628D01*
X199923Y-1049515D01*
X199375Y-1050040D01*
X198983Y-1050670D01*
X198670Y-1051720D01*
X198592Y-1052665D01*
X198748Y-1053610D01*
X198983Y-1054240D01*
X199453Y-1054870D01*
X200002Y-1055290D01*
X200550Y-1055500D01*
X201098D01*
X201647Y-1055290D01*
X202117Y-1054975D01*
X202508Y-1054555D01*
G01X206850Y-1055710D02*
X206693Y-1055605D01*
Y-1055395D01*
X206850Y-1055290D01*
X207007Y-1055395D01*
Y-1055605D01*
X206850Y-1055710D01*
G01X213542Y-1057600D02*
X214325Y-1056550D01*
X214717Y-1055500D01*
Y-1051300D01*
X214325Y-1050250D01*
X213542Y-1049200D01*
G01X47548Y-1035500D02*
Y-1029200D01*
X51152Y-1035500D01*
Y-1029200D01*
G01X55650Y-1035500D02*
X55023Y-1035395D01*
X54475Y-1034975D01*
X54005Y-1034345D01*
X53692Y-1033610D01*
X53535Y-1032770D01*
Y-1031930D01*
X53692Y-1031090D01*
X54005Y-1030355D01*
X54475Y-1029725D01*
X55023Y-1029305D01*
X55650Y-1029200D01*
X56277Y-1029305D01*
X56825Y-1029725D01*
X57295Y-1030355D01*
X57608Y-1031090D01*
X57765Y-1031930D01*
Y-1032770D01*
X57608Y-1033610D01*
X57295Y-1034345D01*
X56825Y-1034975D01*
X56277Y-1035395D01*
X55650Y-1035500D01*
G01X61950Y-1035710D02*
X61793Y-1035605D01*
Y-1035395D01*
X61950Y-1035290D01*
X62107Y-1035395D01*
Y-1035605D01*
X61950Y-1035710D01*
G01X66762Y-1030250D02*
X67232Y-1029620D01*
X67780Y-1029305D01*
X68407Y-1029200D01*
X69190Y-1029410D01*
X69738Y-1029935D01*
X69895Y-1030565D01*
X69817Y-1031195D01*
X69503Y-1031720D01*
X67937Y-1032770D01*
X67232Y-1033505D01*
X66762Y-1034555D01*
X66605Y-1035500D01*
X69895D01*
G01X74550D02*
Y-1029200D01*
X73610Y-1030460D01*
G01Y-1035500D02*
X75490D01*
G01X80850D02*
Y-1029200D01*
X79910Y-1030460D01*
G01Y-1035500D02*
X81790D01*
G01X86993Y-1036655D02*
X87307Y-1035290D01*
G01X91100Y-1029200D02*
X92197Y-1035500D01*
X93450Y-1029200D01*
X94703Y-1035500D01*
X95800Y-1029200D01*
G01X101317Y-1035500D02*
X98183D01*
Y-1029200D01*
X101317D01*
G01X100063Y-1032245D02*
X98183D01*
G01X104248Y-1035500D02*
Y-1029200D01*
X107852Y-1035500D01*
Y-1029200D01*
G01X110705Y-1035500D02*
Y-1029200D01*
G01X113995D02*
Y-1035500D01*
G01Y-1032350D02*
X110705D01*
G01X116927Y-1029200D02*
Y-1033715D01*
X117240Y-1034660D01*
X117867Y-1035290D01*
X118650Y-1035500D01*
X119433Y-1035290D01*
X120060Y-1034660D01*
X120373Y-1033715D01*
Y-1029200D01*
G01X122992Y-1035500D02*
X124950Y-1029200D01*
X126908Y-1035500D01*
G01X126203Y-1033295D02*
X123697D01*
G01X136062Y-1030250D02*
X136532Y-1029620D01*
X137080Y-1029305D01*
X137707Y-1029200D01*
X138490Y-1029410D01*
X139038Y-1029935D01*
X139195Y-1030565D01*
X139117Y-1031195D01*
X138803Y-1031720D01*
X137237Y-1032770D01*
X136532Y-1033505D01*
X136062Y-1034555D01*
X135905Y-1035500D01*
X139195D01*
G01X142048D02*
Y-1029200D01*
X145652Y-1035500D01*
Y-1029200D01*
G01X148427Y-1035500D02*
Y-1029200D01*
X149993D01*
X150620Y-1029515D01*
X151090Y-1029935D01*
X151482Y-1030565D01*
X151795Y-1031300D01*
X151873Y-1032350D01*
X151795Y-1033400D01*
X151482Y-1034135D01*
X151090Y-1034765D01*
X150620Y-1035185D01*
X149993Y-1035500D01*
X148427D01*
G01X161183D02*
Y-1029200D01*
X163142D01*
X163768Y-1029515D01*
X164160Y-1029935D01*
X164317Y-1030775D01*
X164160Y-1031615D01*
X163690Y-1032140D01*
X163142Y-1032455D01*
X161183D01*
G01X163142D02*
X164317Y-1035500D01*
G01X167327D02*
Y-1029200D01*
X168893D01*
X169520Y-1029515D01*
X169990Y-1029935D01*
X170382Y-1030565D01*
X170695Y-1031300D01*
X170773Y-1032350D01*
X170695Y-1033400D01*
X170382Y-1034135D01*
X169990Y-1034765D01*
X169520Y-1035185D01*
X168893Y-1035500D01*
X167327D01*
G01X175350Y-1035710D02*
X175193Y-1035605D01*
Y-1035395D01*
X175350Y-1035290D01*
X175507Y-1035395D01*
Y-1035605D01*
X175350Y-1035710D01*
G01X256400Y-1037500D02*
Y-1029500D01*
X259000Y-1036167D01*
X261600Y-1029500D01*
Y-1037500D01*
G01X264500D02*
X267000Y-1029500D01*
X269500Y-1037500D01*
G01X268600Y-1034700D02*
X265400D01*
G01X272900Y-1036434D02*
X273700Y-1037100D01*
X274600Y-1037500D01*
X275400D01*
X276200Y-1037100D01*
X276800Y-1036434D01*
X277100Y-1035500D01*
X276900Y-1034567D01*
X276400Y-1033767D01*
X275500Y-1033233D01*
X274300Y-1032967D01*
X273600Y-1032433D01*
X273300Y-1031500D01*
X273500Y-1030567D01*
X274000Y-1029900D01*
X274700Y-1029500D01*
X275400D01*
X276100Y-1029767D01*
X276700Y-1030433D01*
G01X280800Y-1037500D02*
Y-1029500D01*
G01X284600D02*
X280800Y-1034434D01*
G01X285200Y-1037500D02*
X282500Y-1032167D01*
G01X289700Y-1034833D02*
X292300D01*
G01X299000Y-1029500D02*
Y-1037500D01*
G01X296700Y-1029500D02*
X301300D01*
G01X307000Y-1037500D02*
X306200Y-1037367D01*
X305500Y-1036833D01*
X304900Y-1036033D01*
X304500Y-1035100D01*
X304300Y-1034033D01*
Y-1032967D01*
X304500Y-1031900D01*
X304900Y-1030967D01*
X305500Y-1030167D01*
X306200Y-1029633D01*
X307000Y-1029500D01*
X307800Y-1029633D01*
X308500Y-1030167D01*
X309100Y-1030967D01*
X309500Y-1031900D01*
X309700Y-1032967D01*
Y-1034033D01*
X309500Y-1035100D01*
X309100Y-1036033D01*
X308500Y-1036833D01*
X307800Y-1037367D01*
X307000Y-1037500D01*
G01X313000D02*
Y-1029500D01*
X315400D01*
X316200Y-1029900D01*
X316800Y-1030833D01*
X317000Y-1031900D01*
X316800Y-1032967D01*
X316300Y-1033767D01*
X315400Y-1034167D01*
X313000D01*
G01X243000Y-1004500D02*
Y-1012500D01*
X247000D01*
G01X254800D02*
Y-1007167D01*
G01Y-1008100D02*
X254400Y-1007567D01*
X253800Y-1007300D01*
X253100Y-1007167D01*
X252400Y-1007433D01*
X251800Y-1007967D01*
X251400Y-1008767D01*
X251200Y-1009833D01*
X251400Y-1010900D01*
X251800Y-1011700D01*
X252400Y-1012233D01*
X253100Y-1012500D01*
X253800Y-1012367D01*
X254400Y-1011967D01*
X254800Y-1011434D01*
G01X258900Y-1014900D02*
X259500Y-1015167D01*
X260300Y-1014900D01*
X260800Y-1014367D01*
X261200Y-1013700D01*
X261800Y-1011567D01*
X263100Y-1007167D01*
G01X259900D02*
X261800Y-1011567D01*
G01X267500Y-1008900D02*
X270700D01*
X270400Y-1007967D01*
X269900Y-1007433D01*
X269200Y-1007167D01*
X268500Y-1007300D01*
X267900Y-1007700D01*
X267500Y-1008633D01*
X267300Y-1009434D01*
Y-1010233D01*
X267500Y-1011033D01*
X268000Y-1011833D01*
X268600Y-1012367D01*
X269300Y-1012500D01*
X270000Y-1012233D01*
X270700Y-1011434D01*
G01X275600Y-1012500D02*
Y-1007167D01*
G01Y-1008233D02*
X276100Y-1007700D01*
X276600Y-1007300D01*
X277300Y-1007167D01*
X277800Y-1007300D01*
X278400Y-1007700D01*
G01X262100Y-1054500D02*
X265900D01*
X262100Y-1062500D01*
X265900D01*
G01X272000Y-1057167D02*
Y-1062500D01*
G01Y-1055033D02*
X271800Y-1054900D01*
Y-1054633D01*
X272000Y-1054500D01*
X272200Y-1054633D01*
Y-1054900D01*
X272000Y-1055033D01*
G01X278700Y-1059833D02*
X281300D01*
G01X286200Y-1065167D02*
Y-1057167D01*
G01Y-1058367D02*
X286700Y-1057700D01*
X287200Y-1057300D01*
X288000Y-1057167D01*
X288700Y-1057300D01*
X289400Y-1057967D01*
X289700Y-1058900D01*
X289800Y-1059833D01*
X289700Y-1060767D01*
X289400Y-1061700D01*
X288800Y-1062233D01*
X288000Y-1062500D01*
X287300Y-1062367D01*
X286600Y-1061967D01*
X286200Y-1061434D01*
G01X296000Y-1057167D02*
Y-1062500D01*
G01Y-1055033D02*
X295800Y-1054900D01*
Y-1054633D01*
X296000Y-1054500D01*
X296200Y-1054633D01*
Y-1054900D01*
X296000Y-1055033D01*
G01X302300Y-1062500D02*
Y-1057167D01*
G01Y-1058500D02*
X302700Y-1057833D01*
X303300Y-1057300D01*
X304100Y-1057167D01*
X304800Y-1057300D01*
X305400Y-1057833D01*
X305700Y-1058767D01*
Y-1062500D01*
G01X310600Y-1064500D02*
X311300Y-1065033D01*
X312100Y-1065167D01*
X312800Y-1065033D01*
X313400Y-1064367D01*
X313800Y-1063433D01*
Y-1057167D01*
G01Y-1058233D02*
X313400Y-1057700D01*
X312800Y-1057300D01*
X312100Y-1057167D01*
X311300Y-1057433D01*
X310800Y-1057967D01*
X310400Y-1058900D01*
X310200Y-1059833D01*
X310300Y-1060633D01*
X310700Y-1061567D01*
X311300Y-1062233D01*
X312100Y-1062500D01*
X312700Y-1062367D01*
X313400Y-1061833D01*
X313800Y-1061300D01*
G01X369600Y-1055833D02*
X370200Y-1055033D01*
X370900Y-1054633D01*
X371700Y-1054500D01*
X372700Y-1054767D01*
X373400Y-1055433D01*
X373600Y-1056233D01*
X373500Y-1057034D01*
X373100Y-1057700D01*
X371100Y-1059033D01*
X370200Y-1059967D01*
X369600Y-1061300D01*
X369400Y-1062500D01*
X373600D01*
G01X379500Y-1054500D02*
X378700Y-1054767D01*
X378100Y-1055433D01*
X377700Y-1056233D01*
X377400Y-1057300D01*
X377300Y-1058500D01*
X377400Y-1059700D01*
X377700Y-1060767D01*
X378100Y-1061567D01*
X378700Y-1062233D01*
X379500Y-1062500D01*
X380300Y-1062233D01*
X380900Y-1061567D01*
X381300Y-1060767D01*
X381600Y-1059700D01*
X381700Y-1058500D01*
X381600Y-1057300D01*
X381300Y-1056233D01*
X380900Y-1055433D01*
X380300Y-1054767D01*
X379500Y-1054500D01*
G01X385600Y-1055833D02*
X386200Y-1055033D01*
X386900Y-1054633D01*
X387700Y-1054500D01*
X388700Y-1054767D01*
X389400Y-1055433D01*
X389600Y-1056233D01*
X389500Y-1057034D01*
X389100Y-1057700D01*
X387100Y-1059033D01*
X386200Y-1059967D01*
X385600Y-1061300D01*
X385400Y-1062500D01*
X389600D01*
G01X393600Y-1055833D02*
X394200Y-1055033D01*
X394900Y-1054633D01*
X395700Y-1054500D01*
X396700Y-1054767D01*
X397400Y-1055433D01*
X397600Y-1056233D01*
X397500Y-1057034D01*
X397100Y-1057700D01*
X395100Y-1059033D01*
X394200Y-1059967D01*
X393600Y-1061300D01*
X393400Y-1062500D01*
X397600D01*
G01X401700Y-1062767D02*
X405300Y-1054500D01*
G01X411500Y-1062500D02*
Y-1054500D01*
X410300Y-1056100D01*
G01Y-1062500D02*
X412700D01*
G01X417600Y-1055833D02*
X418200Y-1055033D01*
X418900Y-1054633D01*
X419700Y-1054500D01*
X420700Y-1054767D01*
X421400Y-1055433D01*
X421600Y-1056233D01*
X421500Y-1057034D01*
X421100Y-1057700D01*
X419100Y-1059033D01*
X418200Y-1059967D01*
X417600Y-1061300D01*
X417400Y-1062500D01*
X421600D01*
G01X425700Y-1062767D02*
X429300Y-1054500D01*
G01X435500Y-1062500D02*
Y-1054500D01*
X434300Y-1056100D01*
G01Y-1062500D02*
X436700D01*
G01X441300Y-1060900D02*
X441900Y-1061833D01*
X442700Y-1062367D01*
X443600Y-1062500D01*
X444400Y-1062367D01*
X445200Y-1061700D01*
X445700Y-1060900D01*
X445800Y-1060100D01*
X445600Y-1059167D01*
X444900Y-1058500D01*
X444200Y-1058233D01*
X443300D01*
G01X444200D02*
X444800Y-1057833D01*
X445300Y-1057167D01*
X445500Y-1056367D01*
X445300Y-1055567D01*
X444800Y-1054900D01*
X443900Y-1054500D01*
X443000Y-1054633D01*
X442100Y-1055167D01*
G01X369300Y-1040000D02*
Y-1032000D01*
X371300D01*
X372100Y-1032400D01*
X372700Y-1032933D01*
X373200Y-1033733D01*
X373600Y-1034667D01*
X373700Y-1036000D01*
X373600Y-1037333D01*
X373200Y-1038267D01*
X372700Y-1039067D01*
X372100Y-1039600D01*
X371300Y-1040000D01*
X369300D01*
G01X377000D02*
X379500Y-1032000D01*
X382000Y-1040000D01*
G01X381100Y-1037200D02*
X377900D01*
G01X385600Y-1040000D02*
Y-1032000D01*
X389400D01*
G01X388000Y-1035867D02*
X385600D01*
G01X395500Y-1032000D02*
X394700Y-1032267D01*
X394100Y-1032933D01*
X393700Y-1033733D01*
X393400Y-1034800D01*
X393300Y-1036000D01*
X393400Y-1037200D01*
X393700Y-1038267D01*
X394100Y-1039067D01*
X394700Y-1039733D01*
X395500Y-1040000D01*
X396300Y-1039733D01*
X396900Y-1039067D01*
X397300Y-1038267D01*
X397600Y-1037200D01*
X397700Y-1036000D01*
X397600Y-1034800D01*
X397300Y-1033733D01*
X396900Y-1032933D01*
X396300Y-1032267D01*
X395500Y-1032000D01*
G01X403500D02*
Y-1040000D01*
G01X401200Y-1032000D02*
X405800D01*
G01X409500Y-1040000D02*
Y-1032000D01*
X411900D01*
X412700Y-1032400D01*
X413300Y-1033333D01*
X413500Y-1034400D01*
X413300Y-1035467D01*
X412800Y-1036267D01*
X411900Y-1036667D01*
X409500D01*
G01X420300Y-1035733D02*
X420700Y-1035333D01*
X421000Y-1034667D01*
X421200Y-1033733D01*
X421000Y-1032933D01*
X420600Y-1032400D01*
X419900Y-1032000D01*
X417200D01*
Y-1040000D01*
X420500D01*
X421200Y-1039467D01*
X421600Y-1038667D01*
X421800Y-1037733D01*
X421600Y-1036800D01*
X421000Y-1036000D01*
X420300Y-1035733D01*
X417200D01*
G01X427500Y-1040000D02*
Y-1032000D01*
X426300Y-1033600D01*
G01Y-1040000D02*
X428700D01*
G01X433000D02*
X435500Y-1032000D01*
X438000Y-1040000D01*
G01X437100Y-1037200D02*
X433900D01*
G01X441600Y-1040000D02*
Y-1032000D01*
X445400D01*
G01X444000Y-1035867D02*
X441600D01*
G01X451500Y-1032000D02*
X450700Y-1032267D01*
X450100Y-1032933D01*
X449700Y-1033733D01*
X449400Y-1034800D01*
X449300Y-1036000D01*
X449400Y-1037200D01*
X449700Y-1038267D01*
X450100Y-1039067D01*
X450700Y-1039733D01*
X451500Y-1040000D01*
X452300Y-1039733D01*
X452900Y-1039067D01*
X453300Y-1038267D01*
X453600Y-1037200D01*
X453700Y-1036000D01*
X453600Y-1034800D01*
X453300Y-1033733D01*
X452900Y-1032933D01*
X452300Y-1032267D01*
X451500Y-1032000D01*
G01X389600Y-1012500D02*
Y-1004500D01*
X393400D01*
G01X392000Y-1008367D02*
X389600D01*
G01X399500Y-1004500D02*
X398700Y-1004767D01*
X398100Y-1005433D01*
X397700Y-1006233D01*
X397400Y-1007300D01*
X397300Y-1008500D01*
X397400Y-1009700D01*
X397700Y-1010767D01*
X398100Y-1011567D01*
X398700Y-1012233D01*
X399500Y-1012500D01*
X400300Y-1012233D01*
X400900Y-1011567D01*
X401300Y-1010767D01*
X401600Y-1009700D01*
X401700Y-1008500D01*
X401600Y-1007300D01*
X401300Y-1006233D01*
X400900Y-1005433D01*
X400300Y-1004767D01*
X399500Y-1004500D01*
G01X407500D02*
Y-1012500D01*
G01X405200Y-1004500D02*
X409800D01*
G01X412500Y-1015167D02*
X418500D01*
G01X421500Y-1012500D02*
Y-1004500D01*
X423900D01*
X424700Y-1004900D01*
X425300Y-1005833D01*
X425500Y-1006900D01*
X425300Y-1007967D01*
X424800Y-1008767D01*
X423900Y-1009167D01*
X421500D01*
G01X429300Y-1012500D02*
Y-1004500D01*
X431300D01*
X432100Y-1004900D01*
X432700Y-1005433D01*
X433200Y-1006233D01*
X433600Y-1007167D01*
X433700Y-1008500D01*
X433600Y-1009833D01*
X433200Y-1010767D01*
X432700Y-1011567D01*
X432100Y-1012100D01*
X431300Y-1012500D01*
X429300D01*
G01X440300Y-1008233D02*
X440700Y-1007833D01*
X441000Y-1007167D01*
X441200Y-1006233D01*
X441000Y-1005433D01*
X440600Y-1004900D01*
X439900Y-1004500D01*
X437200D01*
Y-1012500D01*
X440500D01*
X441200Y-1011967D01*
X441600Y-1011167D01*
X441800Y-1010233D01*
X441600Y-1009300D01*
X441000Y-1008500D01*
X440300Y-1008233D01*
X437200D01*
G01X444500Y-1015167D02*
X450500D01*
G01X456300Y-1008233D02*
X456700Y-1007833D01*
X457000Y-1007167D01*
X457200Y-1006233D01*
X457000Y-1005433D01*
X456600Y-1004900D01*
X455900Y-1004500D01*
X453200D01*
Y-1012500D01*
X456500D01*
X457200Y-1011967D01*
X457600Y-1011167D01*
X457800Y-1010233D01*
X457600Y-1009300D01*
X457000Y-1008500D01*
X456300Y-1008233D01*
X453200D01*
G01X461300Y-1012500D02*
Y-1004500D01*
X463300D01*
X464100Y-1004900D01*
X464700Y-1005433D01*
X465200Y-1006233D01*
X465600Y-1007167D01*
X465700Y-1008500D01*
X465600Y-1009833D01*
X465200Y-1010767D01*
X464700Y-1011567D01*
X464100Y-1012100D01*
X463300Y-1012500D01*
X461300D01*
G01X468500Y-1015167D02*
X474500D01*
G01X480100Y-1008500D02*
X482100D01*
Y-1010900D01*
X481500Y-1011700D01*
X480800Y-1012233D01*
X479800Y-1012500D01*
X478800Y-1012233D01*
X478100Y-1011700D01*
X477500Y-1010900D01*
X477100Y-1009967D01*
X476900Y-1008900D01*
Y-1007967D01*
X477100Y-1007167D01*
X477500Y-1006233D01*
X478100Y-1005433D01*
X478700Y-1004900D01*
X479500Y-1004500D01*
X480200D01*
X481000Y-1004767D01*
X481600Y-1005300D01*
G01X485500Y-1012500D02*
Y-1004500D01*
X487900D01*
X488700Y-1004900D01*
X489300Y-1005833D01*
X489500Y-1006900D01*
X489300Y-1007967D01*
X488800Y-1008767D01*
X487900Y-1009167D01*
X485500D01*
G01X493300Y-1004500D02*
Y-1010233D01*
X493700Y-1011434D01*
X494500Y-1012233D01*
X495500Y-1012500D01*
X496500Y-1012233D01*
X497300Y-1011434D01*
X497700Y-1010233D01*
Y-1004500D01*
G01X458000Y-1065500D02*
Y-1057500D01*
X456800Y-1059100D01*
G01Y-1065500D02*
X459200D01*
G01X464100Y-1062167D02*
X464800Y-1061233D01*
X465400Y-1060700D01*
X466200Y-1060433D01*
X466900Y-1060700D01*
X467400Y-1061233D01*
X467800Y-1062033D01*
X467900Y-1062967D01*
X467800Y-1063767D01*
X467400Y-1064567D01*
X466800Y-1065233D01*
X466100Y-1065500D01*
X465300Y-1065233D01*
X464600Y-1064434D01*
X464200Y-1063233D01*
X464100Y-1061900D01*
X464300Y-1060167D01*
X464600Y-1059233D01*
X465100Y-1058300D01*
X465800Y-1057633D01*
X466500Y-1057500D01*
X467200Y-1057767D01*
X467700Y-1058433D01*
G01X474000Y-1065767D02*
X473800Y-1065633D01*
Y-1065367D01*
X474000Y-1065233D01*
X474200Y-1065367D01*
Y-1065633D01*
X474000Y-1065767D01*
G01X480100Y-1062167D02*
X480800Y-1061233D01*
X481400Y-1060700D01*
X482200Y-1060433D01*
X482900Y-1060700D01*
X483400Y-1061233D01*
X483800Y-1062033D01*
X483900Y-1062967D01*
X483800Y-1063767D01*
X483400Y-1064567D01*
X482800Y-1065233D01*
X482100Y-1065500D01*
X481300Y-1065233D01*
X480600Y-1064434D01*
X480200Y-1063233D01*
X480100Y-1061900D01*
X480300Y-1060167D01*
X480600Y-1059233D01*
X481100Y-1058300D01*
X481800Y-1057633D01*
X482500Y-1057500D01*
X483200Y-1057767D01*
X483700Y-1058433D01*
G01X503000Y-1065500D02*
Y-1057500D01*
X501800Y-1059100D01*
G01Y-1065500D02*
X504200D01*
G01X510800D02*
X511000Y-1063767D01*
X511300Y-1062300D01*
X511700Y-1060967D01*
X512200Y-1059500D01*
X513000Y-1057500D01*
X509000D01*
G01X519000Y-1065767D02*
X518800Y-1065633D01*
Y-1065367D01*
X519000Y-1065233D01*
X519200Y-1065367D01*
Y-1065633D01*
X519000Y-1065767D01*
G01X525100Y-1058833D02*
X525700Y-1058033D01*
X526400Y-1057633D01*
X527200Y-1057500D01*
X528200Y-1057767D01*
X528900Y-1058433D01*
X529100Y-1059233D01*
X529000Y-1060034D01*
X528600Y-1060700D01*
X526600Y-1062033D01*
X525700Y-1062967D01*
X525100Y-1064300D01*
X524900Y-1065500D01*
X529100D01*
G01X523100Y-1040500D02*
Y-1032500D01*
X526900D01*
G01X525500Y-1036367D02*
X523100D01*
G54D45*
X564213Y155300D03*
Y287500D03*
X604483Y300000D03*
X666667Y256000D03*
X657167Y251500D03*
Y256000D03*
Y260500D03*
Y266000D03*
X666667Y251500D03*
X680583Y298500D03*
X661983Y322500D03*
X691483Y178500D03*
X730294Y300595D03*
X878083Y362000D03*
Y382000D03*
X1069583Y307500D03*
Y311500D03*
X1085583Y251500D03*
X1098583Y291500D03*
Y287500D03*
X1108083Y296000D03*
X1149483Y251500D03*
X1627753Y119140D03*
X1629483Y178000D03*
Y172500D03*
X1631483Y167500D03*
Y163500D03*
X1707983Y134500D03*
Y129500D03*
X1695483Y148000D03*
Y164500D03*
Y170000D03*
Y175500D03*
Y153500D03*
Y159000D03*
Y186500D03*
X1683483D03*
X1695483Y181000D03*
X1727183Y88000D03*
X1716183D03*
X1727183Y99000D03*
Y93500D03*
X1716183Y99000D03*
Y93500D03*
X1718983Y114500D03*
Y109500D03*
Y119500D03*
X1725983Y175000D03*
Y183500D03*
X1734983Y201500D03*
X1714083Y189500D03*
X1731983Y250000D03*
X1762983Y181500D03*
X1770483Y124500D03*
Y129500D03*
X1769983Y174000D03*
X1774763Y343970D03*
X1774883Y356300D03*
G54D36*
X387060Y55500D03*
X394540D03*
X590760Y318000D03*
X598240D03*
X696760Y178000D03*
X704240D03*
X1031840Y190500D03*
X1024360D03*
X1628840Y202500D03*
X1621360D03*
G54D27*
X231600Y81000D03*
X1212478Y300181D03*
X1529100Y78500D03*
G54D81*
X1751389Y357827D03*
X1758389D03*
X1751389Y350127D03*
X1758389D03*
X1765600Y370000D03*
Y363000D03*
X1751389Y365527D03*
X1758389D03*
X1751389Y373227D03*
X1758389D03*
X1772600Y370000D03*
Y363000D03*
G54D54*
X822087Y88484D03*
Y313484D03*
X940197Y88484D03*
Y313484D03*
G54D63*
X1637601Y113200D03*
X1641144D03*
X1644687D03*
X1648231D03*
G54D72*
X1733711Y143661D03*
Y146220D03*
Y159161D03*
Y161720D03*
Y164280D03*
Y166839D03*
Y148780D03*
Y151339D03*
X1751289Y146220D03*
Y143661D03*
Y166839D03*
Y164280D03*
Y161720D03*
Y159161D03*
Y151339D03*
Y148780D03*
G54D18*
X137303Y664685D03*
X223622Y617441D03*
X274646Y8012D03*
X303150Y617441D03*
X1465197Y8012D03*
X1484252Y617441D03*
X1540157D03*
X1568406Y664685D03*
G54D46*
X631000Y313760D03*
Y321240D03*
G54D55*
X822087Y88484D03*
Y313484D03*
X940197Y88484D03*
Y313484D03*
G54D73*
X1737677Y177500D03*
Y173760D03*
Y181240D03*
X1747323Y173760D03*
Y181240D03*
G54D64*
X1634451Y111232D03*
Y115168D03*
G54D28*
X208000Y115517D03*
X330500Y69017D03*
X326000D03*
X649500Y257517D03*
X653500Y327017D03*
X676500Y332017D03*
X680500D03*
X1037600Y189017D03*
X1499228Y69018D03*
X1503728D03*
X1524500Y99017D03*
X1628960Y108174D03*
X1627770Y127457D03*
X1645280Y127517D03*
X1638770Y127457D03*
X1631770D03*
X1641000Y201517D03*
X1629600Y192517D03*
X1649270Y127457D03*
X1690100Y132917D03*
X1700100Y121917D03*
X1707200Y160517D03*
X1721000Y145017D03*
Y160517D03*
X1764000Y145017D03*
Y160517D03*
X1746102Y328540D03*
X1852164Y421755D03*
X1837164D03*
X1847164D03*
X1842164D03*
G54D19*
X156785Y110251D03*
X176785D03*
X1555500Y104251D03*
X1575500D03*
G54D37*
X462338Y61900D03*
Y81900D03*
Y106300D03*
Y126300D03*
Y150700D03*
Y170700D03*
Y195100D03*
Y215100D03*
Y239500D03*
Y259500D03*
Y283900D03*
Y303900D03*
X1299946Y81900D03*
Y61900D03*
Y106300D03*
Y126300D03*
Y170700D03*
Y150700D03*
Y195100D03*
Y215100D03*
Y239500D03*
Y259500D03*
Y283900D03*
Y303900D03*
G54D82*
X1751706Y336741D03*
G54D29*
X208000Y103016D03*
X317000Y69016D03*
X321500D03*
X392000Y43816D03*
X663500Y314516D03*
X732000Y307516D03*
X1490228Y69017D03*
X1494728D03*
X1622100Y149016D03*
X1618500Y182516D03*
X1653270Y127456D03*
X1690100Y121916D03*
X1685100D03*
X1707500Y195516D03*
X1711600Y145016D03*
X1717100D03*
X1712000Y160516D03*
X1716500D03*
X1768500Y145016D03*
Y160516D03*
X1773000Y145016D03*
Y160516D03*
X1778000Y192516D03*
X1786600Y243516D03*
X1775816Y336590D03*
X1771816D03*
X1779816D03*
G54D38*
X444838Y87700D03*
Y81900D03*
Y132100D03*
Y126300D03*
Y176500D03*
Y170700D03*
Y220900D03*
Y215100D03*
Y265300D03*
Y259500D03*
Y309700D03*
Y303900D03*
X668000Y320900D03*
Y315100D03*
X1317446Y67900D03*
Y62100D03*
Y112300D03*
Y106500D03*
Y156700D03*
Y150900D03*
Y201100D03*
Y195300D03*
Y239700D03*
Y245500D03*
Y289900D03*
Y284100D03*
G54D65*
X1647837Y107688D03*
X1645868D03*
X1643900D03*
X1641932D03*
X1639963D03*
X1637994D03*
X1636026D03*
Y118712D03*
X1637994D03*
X1639963D03*
X1641932D03*
X1643900D03*
X1645868D03*
X1647837D03*
X1651774Y107688D03*
X1649806D03*
Y118712D03*
G54D74*
X1731000Y241630D03*
Y245370D03*
G54D47*
X643941Y324740D03*
X649059D03*
Y317260D03*
X646500D03*
X643941D03*
X725559Y305260D03*
X720441D03*
Y312740D03*
X723000D03*
X725559D03*
G54D83*
X1762730Y340382D03*
Y338808D03*
Y337233D03*
Y335658D03*
Y334083D03*
Y332508D03*
Y330934D03*
G54D56*
X822087Y200984D03*
X940197D03*
G54D66*
X1643500Y152925D03*
Y155484D03*
Y158043D03*
Y160602D03*
Y163161D03*
Y165720D03*
Y168280D03*
Y170839D03*
Y173398D03*
Y175957D03*
Y178516D03*
Y181075D03*
X1666500Y178516D03*
Y175957D03*
Y173398D03*
Y170839D03*
Y168280D03*
Y165720D03*
Y163161D03*
Y160602D03*
Y158043D03*
Y155484D03*
Y152925D03*
Y181075D03*
G54D39*
X502988Y71900D03*
Y116300D03*
Y160700D03*
Y205100D03*
Y249500D03*
Y293900D03*
G54D48*
X666668Y260500D03*
Y264500D03*
X680584Y302500D03*
X695084Y255500D03*
Y251500D03*
X1085584Y255500D03*
X1098584Y296000D03*
Y300500D03*
X1108084Y291500D03*
Y285000D03*
X1118084Y296000D03*
X1108084Y300500D03*
X1200484Y155300D03*
Y288500D03*
X1524984Y114500D03*
X1615484Y173000D03*
Y169500D03*
Y165500D03*
X1627754Y115140D03*
X1635084Y142000D03*
X1629484Y183000D03*
X1655484Y199000D03*
X1667984Y186500D03*
X1683484Y148000D03*
Y175500D03*
Y153500D03*
Y159000D03*
Y164500D03*
Y170000D03*
Y181000D03*
X1705984Y208000D03*
X1718984Y134500D03*
Y129500D03*
X1720984Y168500D03*
Y153000D03*
X1725984Y179500D03*
X1762984Y174000D03*
X1766984Y153000D03*
Y168500D03*
X1750984Y200500D03*
X1757984D03*
X1770484Y109500D03*
X1770584Y116500D03*
X1770484Y104500D03*
X1770584Y120500D03*
X1770484Y134500D03*
X1772484Y200500D03*
X1774794Y328322D03*
X1770764Y322670D03*
X1777784Y322700D03*
X1774892Y348288D03*
X1774794Y332322D03*
G54D57*
X825900Y362200D03*
X866400Y382200D03*
X906900Y362200D03*
G54D75*
X1732870Y392500D03*
X1754130D03*
G54D84*
X1765686Y396020D03*
X1780056D03*
G54D67*
X1653103Y113201D03*
G54D85*
X1848583Y99212D03*
X1848582Y481693D03*
G54D49*
X663701Y260500D03*
Y264500D03*
X677617Y302500D03*
X692117Y255500D03*
Y251500D03*
X1082617Y255500D03*
X1095617Y296000D03*
Y300500D03*
X1105117Y291500D03*
Y285000D03*
X1115117Y296000D03*
X1105117Y300500D03*
X1197517Y155300D03*
Y288500D03*
X1522017Y114500D03*
X1612517Y173000D03*
Y169500D03*
Y165500D03*
X1624787Y115140D03*
X1632117Y142000D03*
X1626517Y183000D03*
X1652517Y199000D03*
X1665017Y186500D03*
X1680517Y148000D03*
Y175500D03*
Y153500D03*
Y159000D03*
Y164500D03*
Y170000D03*
Y181000D03*
X1703017Y208000D03*
X1716017Y134500D03*
Y129500D03*
X1718017Y168500D03*
Y153000D03*
X1723017Y179500D03*
X1767517Y109500D03*
X1767617Y116500D03*
X1767517Y104500D03*
X1767617Y120500D03*
X1767517Y134500D03*
X1760017Y174000D03*
X1764017Y153000D03*
Y168500D03*
X1748017Y200500D03*
X1755017D03*
X1769517D03*
X1767797Y322670D03*
X1771827Y328322D03*
X1774817Y322700D03*
X1771925Y348288D03*
X1771827Y332322D03*
G54D58*
X825900Y382200D03*
Y372200D03*
X866400Y362200D03*
Y372200D03*
X906900Y382200D03*
Y372200D03*
G54D76*
X1746100Y235839D03*
Y253161D03*
G54D68*
X1651774Y118613D03*
G54D59*
X1043360Y197437D03*
X1047100Y189563D03*
X1050840Y197437D03*
X1635340Y149063D03*
X1627860D03*
X1631600Y156937D03*
X1735000Y195937D03*
X1738740Y188063D03*
X1731260D03*
G54D77*
X1759880Y267724D03*
Y312016D03*
G54D86*
X1835739Y99212D03*
X1835738Y481693D03*
G54D69*
X1673000Y114646D03*
Y95354D03*
G54D78*
X1751706Y328965D03*
X1762730Y342351D03*
G54D87*
X1846142Y230433D03*
Y240433D03*
X1856772D03*
Y230433D03*
X1846142Y250433D03*
Y260433D03*
Y270433D03*
X1856772D03*
Y260433D03*
Y250433D03*
X1846142Y280433D03*
Y290433D03*
Y300433D03*
X1856772D03*
Y290433D03*
Y280433D03*
X1848957Y324213D03*
X1843957Y329213D03*
X1848957Y314213D03*
X1843957Y319213D03*
X1853957Y329213D03*
Y319213D03*
X1858957Y324213D03*
Y314213D03*
X1848957Y334213D03*
Y344213D03*
X1843957Y339213D03*
Y349213D03*
X1853957D03*
Y339213D03*
X1858957Y344213D03*
Y334213D03*
G54D79*
X1756037Y330540D03*
X1758399D03*
Y340776D03*
G54D88*
X1851457Y220433D03*
X1856772Y360433D03*
G54D89*
G01X0Y603543D02*
Y19685D01*
G01D02*
G03X19685Y0I19685J0D01*
G01Y623228D02*
G03X0Y603543I0J-19685D01*
G01X19685Y0D02*
X1712598D01*
G01X102362Y623228D02*
X19685D01*
G01X122047Y642913D02*
G02X102362Y623228I-19685J0D01*
G01X141732Y675787D02*
G03X122047Y656102I0J-19685D01*
G01D02*
Y642913D01*
G01X295276Y675787D02*
X141732D01*
G01X326772Y623228D02*
G02X314961Y635039I0J11811D01*
G01D02*
Y656102D01*
G01D02*
G03X295276Y675787I-19685J0D01*
G01X348425Y603543D02*
G03X328740Y623228I-19685J0D01*
G01D02*
X326772D01*
G01X1354331Y405512D02*
X377953D01*
G01D02*
G02X348425Y435039I-1J29528D01*
G01D02*
Y603543D01*
G01X1383858Y435039D02*
G02X1354331Y405512I-29527J0D01*
G01X1383858Y603543D02*
Y435039D01*
G01X1417323Y635039D02*
G02X1405512Y623228I-11811J0D01*
G01D02*
X1403543D01*
G01D02*
G03X1383858Y603543I0J-19685D01*
G01X1437008Y675787D02*
G03X1417323Y656102I0J-19685D01*
G01D02*
Y635039D01*
G01X1590551Y675787D02*
X1437008D01*
G01X1629921Y623228D02*
G02X1610236Y642913I0J19685D01*
G01D02*
Y656102D01*
G01D02*
G03X1590551Y675787I-19685J0D01*
G01X1712598Y623228D02*
X1629921D01*
G01X1712598Y0D02*
G03X1732283Y19685I0J19685D01*
G01D02*
Y46339D01*
G01D02*
G02X1751969Y66024I19685J-1D01*
G01Y518780D02*
G02X1732283Y538465I0J19685D01*
G01D02*
Y603543D01*
G01D02*
G03X1712598Y623228I-19685J0D01*
G01X1751969Y66024D02*
X1854331D01*
G01Y518780D02*
X1751969D01*
G01X1854331Y66024D02*
G03X1874016Y85709I0J19685D01*
G01Y499094D02*
G03X1854331Y518780I-19685J1D01*
G01X1874016Y85709D02*
Y499094D01*
M02*
